FILE_TYPE = MACRO_DRAWING;
SET COLOR_WIRE YELLOW;
SET COLOR_PROP ORANGE;
SET COLOR_DOT WHITE;
SET COLOR_ARC YELLOW;
SET COLOR_BODY GREEN;
SET COLOR_NOTE PURPLE;
SET PROP_DISPLAY VALUE;
SET PAGE_NUMBER P312;
FORCEADD LCMXO3LF9400C5BG484C..2
(-2000 2525);
FORCEPROP 1 LAST PART_NUMBER AJ094000T08
J 0
(-2720 4041);
DISPLAY 0.723404 (-2720 4041);
PAINT GREEN (-2720 4041);
DISPLAY INVISIBLE (-2720 4041);
FORCEPROP 2 LAST PART_TYPE SMLF
J 0
(-2700 4275);
DISPLAY 1.021277 (-2700 4275);
FORCEPROP 2 LAST VALUE LCMXO3LF-9400C-5BG484C
J 0
(-2700 4225);
DISPLAY 1.021277 (-2700 4225);
FORCEPROP 1 LAST MATERIAL IC
J 0
(-2720 3914);
DISPLAY 0.723404 (-2720 3914);
PAINT GREEN (-2720 3914);
FORCEPROP 1 LAST $LOCATION U249
J 0
(-2720 4188);
DISPLAY 0.723404 (-2720 4188);
PAINT GREEN (-2720 4188);
FORCEPROP 0 LASTPIN (-2875 3850) $PN AA2
J 2
(-2885 3860);
DISPLAY 0.680851 (-2885 3860);
PAINT MONO (-2885 3860);
FORCEPROP 0 LASTPIN (-2875 3800) $PN AB2
J 2
(-2885 3810);
DISPLAY 0.680851 (-2885 3810);
PAINT MONO (-2885 3810);
FORCEPROP 0 LASTPIN (-2875 3750) $PN V6
J 2
(-2885 3760);
DISPLAY 0.680851 (-2885 3760);
PAINT MONO (-2885 3760);
FORCEPROP 0 LASTPIN (-2875 3700) $PN U6
J 2
(-2885 3710);
DISPLAY 0.680851 (-2885 3710);
PAINT MONO (-2885 3710);
FORCEPROP 0 LASTPIN (-2875 3650) $PN AA3
J 2
(-2885 3660);
DISPLAY 0.680851 (-2885 3660);
PAINT MONO (-2885 3660);
FORCEPROP 0 LASTPIN (-2875 3600) $PN AB3
J 2
(-2885 3610);
DISPLAY 0.680851 (-2885 3610);
PAINT MONO (-2885 3610);
FORCEPROP 0 LASTPIN (-2875 3550) $PN Y4
J 2
(-2885 3560);
DISPLAY 0.680851 (-2885 3560);
PAINT MONO (-2885 3560);
FORCEPROP 0 LASTPIN (-2875 3500) $PN W5
J 2
(-2885 3510);
DISPLAY 0.680851 (-2885 3510);
PAINT MONO (-2885 3510);
FORCEPROP 0 LASTPIN (-2875 3450) $PN AA4
J 2
(-2885 3460);
DISPLAY 0.680851 (-2885 3460);
PAINT MONO (-2885 3460);
FORCEPROP 0 LASTPIN (-2875 3400) $PN AB4
J 2
(-2885 3410);
DISPLAY 0.680851 (-2885 3410);
PAINT MONO (-2885 3410);
FORCEPROP 0 LASTPIN (-2875 3350) $PN U7
J 2
(-2885 3360);
DISPLAY 0.680851 (-2885 3360);
PAINT MONO (-2885 3360);
FORCEPROP 0 LASTPIN (-2875 3300) $PN T8
J 2
(-2885 3310);
DISPLAY 0.680851 (-2885 3310);
PAINT MONO (-2885 3310);
FORCEPROP 0 LASTPIN (-2875 3250) $PN AA5
J 2
(-2885 3260);
DISPLAY 0.680851 (-2885 3260);
PAINT MONO (-2885 3260);
FORCEPROP 0 LASTPIN (-2875 3200) $PN AB5
J 2
(-2885 3210);
DISPLAY 0.680851 (-2885 3210);
PAINT MONO (-2885 3210);
FORCEPROP 0 LASTPIN (-2875 3150) $PN Y5
J 2
(-2885 3160);
DISPLAY 0.680851 (-2885 3160);
PAINT MONO (-2885 3160);
FORCEPROP 0 LASTPIN (-2875 3100) $PN Y6
J 2
(-2885 3110);
DISPLAY 0.680851 (-2885 3110);
PAINT MONO (-2885 3110);
FORCEPROP 0 LASTPIN (-2875 3050) $PN AA6
J 2
(-2885 3060);
DISPLAY 0.680851 (-2885 3060);
PAINT MONO (-2885 3060);
FORCEPROP 0 LASTPIN (-2875 3000) $PN AB6
J 2
(-2885 3010);
DISPLAY 0.680851 (-2885 3010);
PAINT MONO (-2885 3010);
FORCEPROP 0 LASTPIN (-2875 2950) $PN W6
J 2
(-2885 2960);
DISPLAY 0.680851 (-2885 2960);
PAINT MONO (-2885 2960);
FORCEPROP 0 LASTPIN (-2875 2900) $PN V7
J 2
(-2885 2910);
DISPLAY 0.680851 (-2885 2910);
PAINT MONO (-2885 2910);
FORCEPROP 0 LASTPIN (-2875 2850) $PN AA7
J 2
(-2885 2860);
DISPLAY 0.680851 (-2885 2860);
PAINT MONO (-2885 2860);
FORCEPROP 0 LASTPIN (-2875 2800) $PN AB7
J 2
(-2885 2810);
DISPLAY 0.680851 (-2885 2810);
PAINT MONO (-2885 2810);
FORCEPROP 0 LASTPIN (-2875 2750) $PN V8
J 2
(-2885 2760);
DISPLAY 0.680851 (-2885 2760);
PAINT MONO (-2885 2760);
FORCEPROP 0 LASTPIN (-2875 2700) $PN U8
J 2
(-2885 2710);
DISPLAY 0.680851 (-2885 2710);
PAINT MONO (-2885 2710);
FORCEPROP 0 LASTPIN (-2875 2650) $PN T9
J 2
(-2885 2660);
DISPLAY 0.680851 (-2885 2660);
PAINT MONO (-2885 2660);
FORCEPROP 0 LASTPIN (-2875 2600) $PN U9
J 2
(-2885 2610);
DISPLAY 0.680851 (-2885 2610);
PAINT MONO (-2885 2610);
FORCEPROP 0 LASTPIN (-2875 2550) $PN V9
J 2
(-2885 2560);
DISPLAY 0.680851 (-2885 2560);
PAINT MONO (-2885 2560);
FORCEPROP 0 LASTPIN (-2875 2500) $PN W8
J 2
(-2885 2510);
DISPLAY 0.680851 (-2885 2510);
PAINT MONO (-2885 2510);
FORCEPROP 0 LASTPIN (-2875 2450) $PN AA8
J 2
(-2885 2460);
DISPLAY 0.680851 (-2885 2460);
PAINT MONO (-2885 2460);
FORCEPROP 0 LASTPIN (-2875 2400) $PN AB8
J 2
(-2885 2410);
DISPLAY 0.680851 (-2885 2410);
PAINT MONO (-2885 2410);
FORCEPROP 0 LASTPIN (-2875 2350) $PN Y8
J 2
(-2885 2360);
DISPLAY 0.680851 (-2885 2360);
PAINT MONO (-2885 2360);
FORCEPROP 0 LASTPIN (-2875 2300) $PN W9
J 2
(-2885 2310);
DISPLAY 0.680851 (-2885 2310);
PAINT MONO (-2885 2310);
FORCEPROP 0 LASTPIN (-2875 2250) $PN AA9
J 2
(-2885 2260);
DISPLAY 0.680851 (-2885 2260);
PAINT MONO (-2885 2260);
FORCEPROP 0 LASTPIN (-2875 2200) $PN AB9
J 2
(-2885 2210);
DISPLAY 0.680851 (-2885 2210);
PAINT MONO (-2885 2210);
FORCEPROP 0 LASTPIN (-2875 2150) $PN T10
J 2
(-2885 2160);
DISPLAY 0.680851 (-2885 2160);
PAINT MONO (-2885 2160);
FORCEPROP 0 LASTPIN (-2875 2100) $PN U10
J 2
(-2885 2110);
DISPLAY 0.680851 (-2885 2110);
PAINT MONO (-2885 2110);
FORCEPROP 0 LASTPIN (-2875 2050) $PN V10
J 2
(-2885 2060);
DISPLAY 0.680851 (-2885 2060);
PAINT MONO (-2885 2060);
FORCEPROP 0 LASTPIN (-2875 2000) $PN W10
J 2
(-2885 2010);
DISPLAY 0.680851 (-2885 2010);
PAINT MONO (-2885 2010);
FORCEPROP 0 LASTPIN (-2875 1950) $PN Y9
J 2
(-2885 1960);
DISPLAY 0.680851 (-2885 1960);
PAINT MONO (-2885 1960);
FORCEPROP 0 LASTPIN (-2875 1900) $PN Y10
J 2
(-2885 1910);
DISPLAY 0.680851 (-2885 1910);
PAINT MONO (-2885 1910);
FORCEPROP 0 LASTPIN (-2875 1800) $PN AA10
J 2
(-2885 1810);
DISPLAY 0.680851 (-2885 1810);
PAINT MONO (-2885 1810);
FORCEPROP 0 LASTPIN (-2875 1750) $PN AB10
J 2
(-2885 1760);
DISPLAY 0.680851 (-2885 1760);
PAINT MONO (-2885 1760);
FORCEPROP 0 LASTPIN (-2875 1700) $PN T11
J 2
(-2885 1710);
DISPLAY 0.680851 (-2885 1710);
PAINT MONO (-2885 1710);
FORCEPROP 0 LASTPIN (-2875 1650) $PN U11
J 2
(-2885 1660);
DISPLAY 0.680851 (-2885 1660);
PAINT MONO (-2885 1660);
FORCEPROP 0 LASTPIN (-2875 1600) $PN AA11
J 2
(-2885 1610);
DISPLAY 0.680851 (-2885 1610);
PAINT MONO (-2885 1610);
FORCEPROP 0 LASTPIN (-2875 1550) $PN AB11
J 2
(-2885 1560);
DISPLAY 0.680851 (-2885 1560);
PAINT MONO (-2885 1560);
FORCEPROP 0 LASTPIN (-2875 1500) $PN V11
J 2
(-2885 1510);
DISPLAY 0.680851 (-2885 1510);
PAINT MONO (-2885 1510);
FORCEPROP 0 LASTPIN (-2875 1450) $PN Y11
J 2
(-2885 1460);
DISPLAY 0.680851 (-2885 1460);
PAINT MONO (-2885 1460);
FORCEPROP 0 LASTPIN (-2875 1400) $PN Y12
J 2
(-2885 1410);
DISPLAY 0.680851 (-2885 1410);
PAINT MONO (-2885 1410);
FORCEPROP 0 LASTPIN (-2875 1350) $PN T12
J 2
(-2885 1360);
DISPLAY 0.680851 (-2885 1360);
PAINT MONO (-2885 1360);
FORCEPROP 0 LASTPIN (-2875 1300) $PN U12
J 2
(-2885 1310);
DISPLAY 0.680851 (-2885 1310);
PAINT MONO (-2885 1310);
FORCEPROP 0 LASTPIN (-2875 1250) $PN V12
J 2
(-2885 1260);
DISPLAY 0.680851 (-2885 1260);
PAINT MONO (-2885 1260);
FORCEPROP 0 LASTPIN (-1125 3650) $PN AB12
J 0
(-1115 3660);
DISPLAY 0.680851 (-1115 3660);
PAINT MONO (-1115 3660);
FORCEPROP 0 LASTPIN (-1125 3600) $PN AA12
J 0
(-1115 3610);
DISPLAY 0.680851 (-1115 3610);
PAINT MONO (-1115 3610);
FORCEPROP 0 LASTPIN (-1125 3550) $PN V13
J 0
(-1115 3560);
DISPLAY 0.680851 (-1115 3560);
PAINT MONO (-1115 3560);
FORCEPROP 0 LASTPIN (-1125 3500) $PN U13
J 0
(-1115 3510);
DISPLAY 0.680851 (-1115 3510);
PAINT MONO (-1115 3510);
FORCEPROP 0 LASTPIN (-1125 3450) $PN AB13
J 0
(-1115 3460);
DISPLAY 0.680851 (-1115 3460);
PAINT MONO (-1115 3460);
FORCEPROP 0 LASTPIN (-1125 3400) $PN AA13
J 0
(-1115 3410);
DISPLAY 0.680851 (-1115 3410);
PAINT MONO (-1115 3410);
FORCEPROP 0 LASTPIN (-1125 3350) $PN Y13
J 0
(-1115 3360);
DISPLAY 0.680851 (-1115 3360);
PAINT MONO (-1115 3360);
FORCEPROP 0 LASTPIN (-1125 3300) $PN W13
J 0
(-1115 3310);
DISPLAY 0.680851 (-1115 3310);
PAINT MONO (-1115 3310);
FORCEPROP 0 LASTPIN (-1125 3250) $PN T13
J 0
(-1115 3260);
DISPLAY 0.680851 (-1115 3260);
PAINT MONO (-1115 3260);
FORCEPROP 0 LASTPIN (-1125 3200) $PN T14
J 0
(-1115 3210);
DISPLAY 0.680851 (-1115 3210);
PAINT MONO (-1115 3210);
FORCEPROP 0 LASTPIN (-1125 3150) $PN U14
J 0
(-1115 3160);
DISPLAY 0.680851 (-1115 3160);
PAINT MONO (-1115 3160);
FORCEPROP 0 LASTPIN (-1125 3100) $PN V14
J 0
(-1115 3110);
DISPLAY 0.680851 (-1115 3110);
PAINT MONO (-1115 3110);
FORCEPROP 0 LASTPIN (-1125 3050) $PN AB14
J 0
(-1115 3060);
DISPLAY 0.680851 (-1115 3060);
PAINT MONO (-1115 3060);
FORCEPROP 0 LASTPIN (-1125 3000) $PN AA14
J 0
(-1115 3010);
DISPLAY 0.680851 (-1115 3010);
PAINT MONO (-1115 3010);
FORCEPROP 0 LASTPIN (-1125 2950) $PN Y14
J 0
(-1115 2960);
DISPLAY 0.680851 (-1115 2960);
PAINT MONO (-1115 2960);
FORCEPROP 0 LASTPIN (-1125 2900) $PN W14
J 0
(-1115 2910);
DISPLAY 0.680851 (-1115 2910);
PAINT MONO (-1115 2910);
FORCEPROP 0 LASTPIN (-1125 2850) $PN AB15
J 0
(-1115 2860);
DISPLAY 0.680851 (-1115 2860);
PAINT MONO (-1115 2860);
FORCEPROP 0 LASTPIN (-1125 2800) $PN AA15
J 0
(-1115 2810);
DISPLAY 0.680851 (-1115 2810);
PAINT MONO (-1115 2810);
FORCEPROP 0 LASTPIN (-1125 2750) $PN Y15
J 0
(-1115 2760);
DISPLAY 0.680851 (-1115 2760);
PAINT MONO (-1115 2760);
FORCEPROP 0 LASTPIN (-1125 2700) $PN W15
J 0
(-1115 2710);
DISPLAY 0.680851 (-1115 2710);
PAINT MONO (-1115 2710);
FORCEPROP 0 LASTPIN (-1125 2650) $PN AB16
J 0
(-1115 2660);
DISPLAY 0.680851 (-1115 2660);
PAINT MONO (-1115 2660);
FORCEPROP 0 LASTPIN (-1125 2600) $PN AA16
J 0
(-1115 2610);
DISPLAY 0.680851 (-1115 2610);
PAINT MONO (-1115 2610);
FORCEPROP 0 LASTPIN (-1125 2550) $PN V15
J 0
(-1115 2560);
DISPLAY 0.680851 (-1115 2560);
PAINT MONO (-1115 2560);
FORCEPROP 0 LASTPIN (-1125 2500) $PN U15
J 0
(-1115 2510);
DISPLAY 0.680851 (-1115 2510);
PAINT MONO (-1115 2510);
FORCEPROP 0 LASTPIN (-1125 2450) $PN AB17
J 0
(-1115 2460);
DISPLAY 0.680851 (-1115 2460);
PAINT MONO (-1115 2460);
FORCEPROP 0 LASTPIN (-1125 2400) $PN AA17
J 0
(-1115 2410);
DISPLAY 0.680851 (-1115 2410);
PAINT MONO (-1115 2410);
FORCEPROP 0 LASTPIN (-1125 2350) $PN Y17
J 0
(-1115 2360);
DISPLAY 0.680851 (-1115 2360);
PAINT MONO (-1115 2360);
FORCEPROP 0 LASTPIN (-1125 2300) $PN V16
J 0
(-1115 2310);
DISPLAY 0.680851 (-1115 2310);
PAINT MONO (-1115 2310);
FORCEPROP 0 LASTPIN (-1125 2250) $PN AB18
J 0
(-1115 2260);
DISPLAY 0.680851 (-1115 2260);
PAINT MONO (-1115 2260);
FORCEPROP 0 LASTPIN (-1125 2200) $PN AA18
J 0
(-1115 2210);
DISPLAY 0.680851 (-1115 2210);
PAINT MONO (-1115 2210);
FORCEPROP 0 LASTPIN (-1125 2150) $PN Y18
J 0
(-1115 2160);
DISPLAY 0.680851 (-1115 2160);
PAINT MONO (-1115 2160);
FORCEPROP 0 LASTPIN (-1125 2100) $PN W17
J 0
(-1115 2110);
DISPLAY 0.680851 (-1115 2110);
PAINT MONO (-1115 2110);
FORCEPROP 0 LASTPIN (-1125 2050) $PN AB19
J 0
(-1115 2060);
DISPLAY 0.680851 (-1115 2060);
PAINT MONO (-1115 2060);
FORCEPROP 0 LASTPIN (-1125 2000) $PN AA19
J 0
(-1115 2010);
DISPLAY 0.680851 (-1115 2010);
PAINT MONO (-1115 2010);
FORCEPROP 0 LASTPIN (-1125 1950) $PN T15
J 0
(-1115 1960);
DISPLAY 0.680851 (-1115 1960);
PAINT MONO (-1115 1960);
FORCEPROP 0 LASTPIN (-1125 1900) $PN U16
J 0
(-1115 1910);
DISPLAY 0.680851 (-1115 1910);
PAINT MONO (-1115 1910);
FORCEPROP 0 LASTPIN (-1125 1850) $PN AB20
J 0
(-1115 1860);
DISPLAY 0.680851 (-1115 1860);
PAINT MONO (-1115 1860);
FORCEPROP 0 LASTPIN (-1125 1800) $PN AA20
J 0
(-1115 1810);
DISPLAY 0.680851 (-1115 1810);
PAINT MONO (-1115 1810);
FORCEPROP 0 LASTPIN (-1125 1750) $PN Y19
J 0
(-1115 1760);
DISPLAY 0.680851 (-1115 1760);
PAINT MONO (-1115 1760);
FORCEPROP 0 LASTPIN (-1125 1700) $PN W18
J 0
(-1115 1710);
DISPLAY 0.680851 (-1115 1710);
PAINT MONO (-1115 1710);
FORCEPROP 0 LASTPIN (-1125 1650) $PN AB21
J 0
(-1115 1660);
DISPLAY 0.680851 (-1115 1660);
PAINT MONO (-1115 1660);
FORCEPROP 0 LASTPIN (-1125 1600) $PN AA21
J 0
(-1115 1610);
DISPLAY 0.680851 (-1115 1610);
PAINT MONO (-1115 1610);
FORCEPROP 0 LASTPIN (-1125 1550) $PN V17
J 0
(-1115 1560);
DISPLAY 0.680851 (-1115 1560);
PAINT MONO (-1115 1560);
FORCEPROP 0 LASTPIN (-1125 1500) $PN T16
J 0
(-1115 1510);
DISPLAY 0.680851 (-1115 1510);
PAINT MONO (-1115 1510);
FORCEPROP 1 LAST CDS_LMAN_SYM_OUTLINE -725,1375,725,-1375
J 0
(-2000 2525);
DISPLAY 0.468085 (-2000 2525);
PAINT GREEN (-2000 2525);
DISPLAY INVISIBLE (-2000 2525);
FORCEPROP 1 LAST NEEDS_NO_SIZE TRUE
J 0
(-2000 2525);
DISPLAY 0.723404 (-2000 2525);
PAINT GREEN (-2000 2525);
DISPLAY INVISIBLE (-2000 2525);
FORCEPROP 2 LAST CDS_LIB pure_quanta
J 0
(-2000 2525);
DISPLAY INVISIBLE (-2000 2525);
FORCEPROP 1 LAST PATH I1
J 0
(-2000 2525);
DISPLAY 0.723404 (-2000 2525);
PAINT GREEN (-2000 2525);
DISPLAY INVISIBLE (-2000 2525);
FORCEPROP 0 LAST CDS_LOCATION U249
J 0
(-2700 4325);
DISPLAY 1.021277 (-2700 4325);
DISPLAY INVISIBLE (-2700 4325);
FORCEPROP 0 LAST $SEC 2
J 0
(-2700 4325);
DISPLAY 0.680851 (-2700 4325);
PAINT MONO (-2700 4325);
DISPLAY INVISIBLE (-2700 4325);
FORCEPROP 0 LAST CDS_SEC 2
J 0
(-2700 4325);
DISPLAY 1.021277 (-2700 4325);
DISPLAY INVISIBLE (-2700 4325);
FORCEADD OFFPAGE..1
R 2
(-75 3400);
FORCEPROP 2 LAST $XR0 296 
J 0
(111 3400);
DISPLAY 0.638298 (111 3400);
PAINT MONO (111 3400);
FORCEPROP 2 LAST PATH I10
J 0
(125 3450);
DISPLAY 1.021277 (125 3450);
DISPLAY INVISIBLE (125 3450);
FORCEPROP 1 LAST COMMENT_BODY TRUE
J 2
(-200 3300);
DISPLAY 1.170213 (-200 3300);
PAINT GREEN (-200 3300);
DISPLAY INVISIBLE (-200 3300);
FORCEPROP 1 LAST OFFPAGE TRUE
J 2
(-400 3275);
DISPLAY 1.170213 (-400 3275);
PAINT GREEN (-400 3275);
DISPLAY INVISIBLE (-400 3275);
FORCEPROP 2 LAST CDS_LIB standard
J 0
(-75 3400);
PAINT MONO (-75 3400);
DISPLAY INVISIBLE (-75 3400);
FORCEADD OFFPAGE..1
(-5775 25);
FORCEPROP 2 LAST $XR0 146 
J 0
(-6027 25);
DISPLAY 0.638298 (-6027 25);
PAINT MONO (-6027 25);
FORCEPROP 2 LAST PATH I100
J 0
(-5725 100);
DISPLAY 1.021277 (-5725 100);
DISPLAY INVISIBLE (-5725 100);
FORCEPROP 1 LAST OFFPAGE TRUE
J 0
(-5450 -100);
DISPLAY 0.872340 (-5450 -100);
DISPLAY INVISIBLE (-5450 -100);
FORCEPROP 1 LAST COMMENT_BODY TRUE
J 0
(-5650 -75);
DISPLAY 1.170213 (-5650 -75);
PAINT GREEN (-5650 -75);
DISPLAY INVISIBLE (-5650 -75);
FORCEPROP 2 LAST CDS_LIB standard
J 0
(-5775 25);
DISPLAY INVISIBLE (-5775 25);
FORCEADD OFFPAGE..1
(-5775 -300);
FORCEPROP 2 LAST $XR0 146 
J 0
(-6027 -300);
DISPLAY 0.638298 (-6027 -300);
PAINT MONO (-6027 -300);
FORCEPROP 1 LAST OFFPAGE TRUE
J 0
(-5450 -425);
DISPLAY 0.872340 (-5450 -425);
DISPLAY INVISIBLE (-5450 -425);
FORCEPROP 1 LAST COMMENT_BODY TRUE
J 0
(-5650 -400);
DISPLAY 1.170213 (-5650 -400);
PAINT GREEN (-5650 -400);
DISPLAY INVISIBLE (-5650 -400);
FORCEPROP 2 LAST CDS_LIB standard
J 0
(-5775 -300);
DISPLAY INVISIBLE (-5775 -300);
FORCEPROP 2 LAST PATH I101
J 0
(-5725 -225);
DISPLAY 1.021277 (-5725 -225);
DISPLAY INVISIBLE (-5725 -225);
FORCEADD OFFPAGE..1
(-5775 -125);
FORCEPROP 2 LAST $XR1 227 
J 0
(-6027 -161);
DISPLAY 0.638298 (-6027 -161);
PAINT MONO (-6027 -161);
FORCEPROP 2 LAST $XR0 146 
J 0
(-6027 -125);
DISPLAY 0.638298 (-6027 -125);
PAINT MONO (-6027 -125);
FORCEPROP 2 LAST CDS_LIB standard
J 0
(-5775 -125);
DISPLAY INVISIBLE (-5775 -125);
FORCEPROP 1 LAST COMMENT_BODY TRUE
J 0
(-5650 -225);
DISPLAY 1.170213 (-5650 -225);
PAINT GREEN (-5650 -225);
DISPLAY INVISIBLE (-5650 -225);
FORCEPROP 1 LAST OFFPAGE TRUE
J 0
(-5450 -250);
DISPLAY 0.872340 (-5450 -250);
DISPLAY INVISIBLE (-5450 -250);
FORCEPROP 2 LAST PATH I102
J 0
(-5725 -50);
DISPLAY 1.021277 (-5725 -50);
DISPLAY INVISIBLE (-5725 -50);
FORCEADD Q_RES..1
(-4550 -300);
FORCEPROP 1 LAST PART_NUMBER CS03322FB03
J 0
(-4700 -225);
DISPLAY 0.638298 (-4700 -225);
DISPLAY INVISIBLE (-4700 -225);
FORCEPROP 1 LAST TOLERANCE 1%
J 0
(-4275 -300);
DISPLAY 0.638298 (-4275 -300);
FORCEPROP 1 LAST VALUE 33.2
J 2
(-4300 -300);
DISPLAY 0.638298 (-4300 -300);
FORCEPROP 1 LAST MATERIAL CHIP
J 0
(-4200 -300);
DISPLAY 0.638298 (-4200 -300);
FORCEPROP 1 LAST $LOCATION R4148
J 0
(-4825 -300);
DISPLAY 0.787234 (-4825 -300);
FORCEPROP 1 LASTPIN (-4650 -300) $PN 1
J 0
(-4638 -288);
DISPLAY 0.787234 (-4638 -288);
FORCEPROP 1 LASTPIN (-4450 -300) $PN 2
J 0
(-4488 -288);
DISPLAY 0.787234 (-4488 -288);
FORCEPROP 1 LAST PATH I103
J 0
(-4600 -150);
DISPLAY 0.978723 (-4600 -150);
PAINT WHITE (-4600 -150);
DISPLAY INVISIBLE (-4600 -150);
FORCEPROP 1 LAST WATTAGE 1/16W
J 2
(-4350 -175);
DISPLAY 0.638298 (-4350 -175);
DISPLAY INVISIBLE (-4350 -175);
FORCEPROP 1 LAST PACK_TYPE 0402LF
J 0
(-4700 -175);
DISPLAY 0.638298 (-4700 -175);
DISPLAY INVISIBLE (-4700 -175);
FORCEPROP 2 LAST CDS_LIB pure_quanta
J 0
(-4550 -300);
PAINT MONO (-4550 -300);
DISPLAY INVISIBLE (-4550 -300);
FORCEPROP 2 LAST CDS_LOCATION R4148
J 0
(-4600 -100);
DISPLAY 1.021277 (-4600 -100);
DISPLAY INVISIBLE (-4600 -100);
FORCEPROP 2 LAST $SEC 1
J 0
(-4600 -100);
DISPLAY 0.680851 (-4600 -100);
PAINT MONO (-4600 -100);
DISPLAY INVISIBLE (-4600 -100);
FORCEPROP 2 LAST CDS_SEC 1
J 0
(-4600 -100);
DISPLAY 1.021277 (-4600 -100);
DISPLAY INVISIBLE (-4600 -100);
FORCEADD Q_RES..1
(-4550 -125);
FORCEPROP 1 LAST PART_NUMBER CS03322FB03
J 0
(-4700 -50);
DISPLAY 0.638298 (-4700 -50);
DISPLAY INVISIBLE (-4700 -50);
FORCEPROP 1 LAST VALUE 33.2
J 2
(-4300 -125);
DISPLAY 0.638298 (-4300 -125);
FORCEPROP 1 LAST TOLERANCE 1%
J 0
(-4275 -125);
DISPLAY 0.638298 (-4275 -125);
FORCEPROP 1 LAST MATERIAL CHIP
J 0
(-4200 -125);
DISPLAY 0.638298 (-4200 -125);
FORCEPROP 1 LAST $LOCATION R4147
J 0
(-4825 -125);
DISPLAY 0.787234 (-4825 -125);
FORCEPROP 1 LASTPIN (-4650 -125) $PN 1
J 0
(-4638 -113);
DISPLAY 0.787234 (-4638 -113);
FORCEPROP 1 LASTPIN (-4450 -125) $PN 2
J 0
(-4488 -113);
DISPLAY 0.787234 (-4488 -113);
FORCEPROP 1 LAST PATH I104
J 0
(-4600 25);
DISPLAY 0.978723 (-4600 25);
PAINT WHITE (-4600 25);
DISPLAY INVISIBLE (-4600 25);
FORCEPROP 2 LAST CDS_LIB pure_quanta
J 0
(-4550 -125);
PAINT MONO (-4550 -125);
DISPLAY INVISIBLE (-4550 -125);
FORCEPROP 1 LAST PACK_TYPE 0402LF
J 0
(-4700 0);
DISPLAY 0.638298 (-4700 0);
DISPLAY INVISIBLE (-4700 0);
FORCEPROP 1 LAST WATTAGE 1/16W
J 2
(-4350 0);
DISPLAY 0.638298 (-4350 0);
DISPLAY INVISIBLE (-4350 0);
FORCEPROP 2 LAST CDS_LOCATION R4147
J 0
(-4600 75);
DISPLAY 1.021277 (-4600 75);
DISPLAY INVISIBLE (-4600 75);
FORCEPROP 2 LAST $SEC 1
J 0
(-4600 75);
DISPLAY 0.680851 (-4600 75);
PAINT MONO (-4600 75);
DISPLAY INVISIBLE (-4600 75);
FORCEPROP 2 LAST CDS_SEC 1
J 0
(-4600 75);
DISPLAY 1.021277 (-4600 75);
DISPLAY INVISIBLE (-4600 75);
FORCEADD OFFPAGE..2
(-3175 -300);
FORCEPROP 2 LAST $XR0 215 
J 0
(-2986 -300);
DISPLAY 0.638298 (-2986 -300);
PAINT MONO (-2986 -300);
FORCEPROP 1 LAST OFFPAGE TRUE
J 0
(-2850 -425);
DISPLAY 0.872340 (-2850 -425);
PAINT GREEN (-2850 -425);
DISPLAY INVISIBLE (-2850 -425);
FORCEPROP 1 LAST COMMENT_BODY TRUE
J 0
(-3220 -395);
DISPLAY 0.872340 (-3220 -395);
PAINT PEACH (-3220 -395);
DISPLAY INVISIBLE (-3220 -395);
FORCEPROP 2 LAST CDS_LIB standard
J 0
(-3175 -300);
DISPLAY INVISIBLE (-3175 -300);
FORCEPROP 2 LAST PATH I105
J 0
(-3000 -225);
DISPLAY 1.021277 (-3000 -225);
DISPLAY INVISIBLE (-3000 -225);
FORCEADD OFFPAGE..2
(-3175 -125);
FORCEPROP 2 LAST $XR0 215 
J 0
(-2986 -125);
DISPLAY 0.638298 (-2986 -125);
PAINT MONO (-2986 -125);
FORCEPROP 2 LAST CDS_LIB standard
J 0
(-3175 -125);
DISPLAY INVISIBLE (-3175 -125);
FORCEPROP 1 LAST COMMENT_BODY TRUE
J 0
(-3220 -220);
DISPLAY 0.872340 (-3220 -220);
PAINT PEACH (-3220 -220);
DISPLAY INVISIBLE (-3220 -220);
FORCEPROP 1 LAST OFFPAGE TRUE
J 0
(-2850 -250);
DISPLAY 0.872340 (-2850 -250);
PAINT GREEN (-2850 -250);
DISPLAY INVISIBLE (-2850 -250);
FORCEPROP 2 LAST PATH I106
J 0
(-3000 -50);
DISPLAY 1.021277 (-3000 -50);
DISPLAY INVISIBLE (-3000 -50);
FORCEADD OFFPAGE..1
(-3950 1550);
FORCEPROP 2 LAST $XR0 215 
J 0
(-4202 1550);
DISPLAY 0.638298 (-4202 1550);
PAINT MONO (-4202 1550);
FORCEPROP 2 LAST CDS_LIB standard
J 0
(-3950 1550);
DISPLAY INVISIBLE (-3950 1550);
FORCEPROP 2 LAST PATH I107
J 0
(-3900 1625);
DISPLAY 1.021277 (-3900 1625);
DISPLAY INVISIBLE (-3900 1625);
FORCEPROP 1 LAST COMMENT_BODY TRUE
J 0
(-3825 1450);
DISPLAY 1.170213 (-3825 1450);
PAINT GREEN (-3825 1450);
DISPLAY INVISIBLE (-3825 1450);
FORCEPROP 1 LAST OFFPAGE TRUE
J 0
(-3625 1425);
DISPLAY 0.872340 (-3625 1425);
DISPLAY INVISIBLE (-3625 1425);
FORCEADD OFFPAGE..1
(-3950 1600);
FORCEPROP 2 LAST $XR0 215 
J 0
(-4202 1600);
DISPLAY 0.638298 (-4202 1600);
PAINT MONO (-4202 1600);
FORCEPROP 2 LAST CDS_LIB standard
J 0
(-3950 1600);
DISPLAY INVISIBLE (-3950 1600);
FORCEPROP 2 LAST PATH I108
J 0
(-3900 1675);
DISPLAY 1.021277 (-3900 1675);
DISPLAY INVISIBLE (-3900 1675);
FORCEPROP 1 LAST COMMENT_BODY TRUE
J 0
(-3825 1500);
DISPLAY 1.170213 (-3825 1500);
PAINT GREEN (-3825 1500);
DISPLAY INVISIBLE (-3825 1500);
FORCEPROP 1 LAST OFFPAGE TRUE
J 0
(-3625 1475);
DISPLAY 0.872340 (-3625 1475);
DISPLAY INVISIBLE (-3625 1475);
FORCEADD OFFPAGE..1
(-3950 1650);
FORCEPROP 2 LAST $XR0 215 
J 0
(-4202 1650);
DISPLAY 0.638298 (-4202 1650);
PAINT MONO (-4202 1650);
FORCEPROP 2 LAST CDS_LIB standard
J 0
(-3950 1650);
DISPLAY INVISIBLE (-3950 1650);
FORCEPROP 2 LAST PATH I109
J 0
(-3900 1725);
DISPLAY 1.021277 (-3900 1725);
DISPLAY INVISIBLE (-3900 1725);
FORCEPROP 1 LAST COMMENT_BODY TRUE
J 0
(-3825 1550);
DISPLAY 1.170213 (-3825 1550);
PAINT GREEN (-3825 1550);
DISPLAY INVISIBLE (-3825 1550);
FORCEPROP 1 LAST OFFPAGE TRUE
J 0
(-3625 1525);
DISPLAY 0.872340 (-3625 1525);
DISPLAY INVISIBLE (-3625 1525);
FORCEADD OFFPAGE..1
R 2
(-75 3350);
FORCEPROP 2 LAST $XR0 215 
J 0
(111 3350);
DISPLAY 0.638298 (111 3350);
PAINT MONO (111 3350);
FORCEPROP 2 LAST PATH I11
J 0
(125 3400);
DISPLAY 1.021277 (125 3400);
DISPLAY INVISIBLE (125 3400);
FORCEPROP 2 LAST CDS_LIB standard
J 0
(-75 3350);
DISPLAY INVISIBLE (-75 3350);
FORCEPROP 1 LAST OFFPAGE TRUE
J 2
(-400 3225);
DISPLAY 1.170213 (-400 3225);
PAINT GREEN (-400 3225);
DISPLAY INVISIBLE (-400 3225);
FORCEPROP 1 LAST COMMENT_BODY TRUE
J 2
(-200 3250);
DISPLAY 1.170213 (-200 3250);
PAINT GREEN (-200 3250);
DISPLAY INVISIBLE (-200 3250);
FORCEADD OFFPAGE..1
(-3950 1700);
FORCEPROP 2 LAST $XR0 215 
J 0
(-4202 1700);
DISPLAY 0.638298 (-4202 1700);
PAINT MONO (-4202 1700);
FORCEPROP 2 LAST CDS_LIB standard
J 0
(-3950 1700);
DISPLAY INVISIBLE (-3950 1700);
FORCEPROP 2 LAST PATH I110
J 0
(-3900 1775);
DISPLAY 1.021277 (-3900 1775);
DISPLAY INVISIBLE (-3900 1775);
FORCEPROP 1 LAST OFFPAGE TRUE
J 0
(-3625 1575);
DISPLAY 0.872340 (-3625 1575);
DISPLAY INVISIBLE (-3625 1575);
FORCEPROP 1 LAST COMMENT_BODY TRUE
J 0
(-3825 1600);
DISPLAY 1.170213 (-3825 1600);
PAINT GREEN (-3825 1600);
DISPLAY INVISIBLE (-3825 1600);
FORCEADD OFFPAGE..1
(-3950 1450);
FORCEPROP 2 LAST $XR0 215 
J 0
(-4202 1450);
DISPLAY 0.638298 (-4202 1450);
PAINT MONO (-4202 1450);
FORCEPROP 2 LAST PATH I111
J 0
(-3900 1525);
DISPLAY 1.021277 (-3900 1525);
DISPLAY INVISIBLE (-3900 1525);
FORCEPROP 2 LAST CDS_LIB standard
J 0
(-3950 1450);
DISPLAY INVISIBLE (-3950 1450);
FORCEPROP 1 LAST COMMENT_BODY TRUE
J 0
(-3825 1350);
DISPLAY 1.170213 (-3825 1350);
PAINT GREEN (-3825 1350);
DISPLAY INVISIBLE (-3825 1350);
FORCEPROP 1 LAST OFFPAGE TRUE
J 0
(-3625 1325);
DISPLAY 0.872340 (-3625 1325);
DISPLAY INVISIBLE (-3625 1325);
FORCEADD OFFPAGE..1
(-3950 1500);
FORCEPROP 2 LAST $XR0 215 
J 0
(-4202 1500);
DISPLAY 0.638298 (-4202 1500);
PAINT MONO (-4202 1500);
FORCEPROP 2 LAST PATH I112
J 0
(-3900 1575);
DISPLAY 1.021277 (-3900 1575);
DISPLAY INVISIBLE (-3900 1575);
FORCEPROP 1 LAST OFFPAGE TRUE
J 0
(-3625 1375);
DISPLAY 0.872340 (-3625 1375);
DISPLAY INVISIBLE (-3625 1375);
FORCEPROP 1 LAST COMMENT_BODY TRUE
J 0
(-3825 1400);
DISPLAY 1.170213 (-3825 1400);
PAINT GREEN (-3825 1400);
DISPLAY INVISIBLE (-3825 1400);
FORCEPROP 2 LAST CDS_LIB standard
J 0
(-3950 1500);
DISPLAY INVISIBLE (-3950 1500);
FORCEADD OFFPAGE..2
(-3175 -475);
FORCEPROP 2 LAST $XR0 215 
J 0
(-2986 -475);
DISPLAY 0.638298 (-2986 -475);
PAINT MONO (-2986 -475);
FORCEPROP 2 LAST CDS_LIB standard
J 0
(-3175 -475);
DISPLAY INVISIBLE (-3175 -475);
FORCEPROP 1 LAST COMMENT_BODY TRUE
J 0
(-3220 -570);
DISPLAY 0.872340 (-3220 -570);
PAINT PEACH (-3220 -570);
DISPLAY INVISIBLE (-3220 -570);
FORCEPROP 1 LAST OFFPAGE TRUE
J 0
(-2850 -600);
DISPLAY 0.872340 (-2850 -600);
PAINT GREEN (-2850 -600);
DISPLAY INVISIBLE (-2850 -600);
FORCEPROP 2 LAST PATH I113
J 0
(-2975 -425);
DISPLAY 1.021277 (-2975 -425);
DISPLAY INVISIBLE (-2975 -425);
FORCEADD Q_RES..1
(-4550 -475);
FORCEPROP 1 LAST PART_NUMBER CS03322FB03
J 0
(-4700 -400);
DISPLAY 0.638298 (-4700 -400);
DISPLAY INVISIBLE (-4700 -400);
FORCEPROP 1 LAST MATERIAL CHIP
J 0
(-4200 -475);
DISPLAY 0.638298 (-4200 -475);
FORCEPROP 1 LAST VALUE 33.2
J 2
(-4300 -475);
DISPLAY 0.638298 (-4300 -475);
FORCEPROP 1 LAST TOLERANCE 1%
J 0
(-4275 -475);
DISPLAY 0.638298 (-4275 -475);
FORCEPROP 1 LAST $LOCATION R4157
J 0
(-4825 -475);
DISPLAY 0.787234 (-4825 -475);
FORCEPROP 1 LASTPIN (-4650 -475) $PN 1
J 0
(-4638 -463);
DISPLAY 0.787234 (-4638 -463);
FORCEPROP 1 LASTPIN (-4450 -475) $PN 2
J 0
(-4488 -463);
DISPLAY 0.787234 (-4488 -463);
FORCEPROP 1 LAST PATH I114
J 0
(-4600 -325);
DISPLAY 0.978723 (-4600 -325);
PAINT WHITE (-4600 -325);
DISPLAY INVISIBLE (-4600 -325);
FORCEPROP 2 LAST CDS_LIB pure_quanta
J 0
(-4550 -475);
PAINT MONO (-4550 -475);
DISPLAY INVISIBLE (-4550 -475);
FORCEPROP 1 LAST PACK_TYPE 0402LF
J 0
(-4700 -350);
DISPLAY 0.638298 (-4700 -350);
DISPLAY INVISIBLE (-4700 -350);
FORCEPROP 1 LAST WATTAGE 1/16W
J 2
(-4350 -350);
DISPLAY 0.638298 (-4350 -350);
DISPLAY INVISIBLE (-4350 -350);
FORCEPROP 2 LAST CDS_LOCATION R4157
J 0
(-4600 -275);
DISPLAY 1.021277 (-4600 -275);
DISPLAY INVISIBLE (-4600 -275);
FORCEPROP 2 LAST $SEC 1
J 0
(-4600 -275);
DISPLAY 0.680851 (-4600 -275);
PAINT MONO (-4600 -275);
DISPLAY INVISIBLE (-4600 -275);
FORCEPROP 2 LAST CDS_SEC 1
J 0
(-4600 -275);
DISPLAY 1.021277 (-4600 -275);
DISPLAY INVISIBLE (-4600 -275);
FORCEADD OFFPAGE..1
(-5775 -475);
FORCEPROP 2 LAST $XR1 227 
J 0
(-6027 -511);
DISPLAY 0.638298 (-6027 -511);
PAINT MONO (-6027 -511);
FORCEPROP 2 LAST $XR0 146 
J 0
(-6027 -475);
DISPLAY 0.638298 (-6027 -475);
PAINT MONO (-6027 -475);
FORCEPROP 2 LAST CDS_LIB standard
J 0
(-5775 -475);
DISPLAY INVISIBLE (-5775 -475);
FORCEPROP 1 LAST COMMENT_BODY TRUE
J 0
(-5650 -575);
DISPLAY 1.170213 (-5650 -575);
PAINT GREEN (-5650 -575);
DISPLAY INVISIBLE (-5650 -575);
FORCEPROP 1 LAST OFFPAGE TRUE
J 0
(-5450 -600);
DISPLAY 0.872340 (-5450 -600);
DISPLAY INVISIBLE (-5450 -600);
FORCEPROP 2 LAST PATH I115
J 0
(-6025 -425);
DISPLAY 1.021277 (-6025 -425);
DISPLAY INVISIBLE (-6025 -425);
FORCEADD OFFPAGE..1
(-3950 1400);
FORCEPROP 2 LAST $XR0 215 
J 0
(-4202 1400);
DISPLAY 0.638298 (-4202 1400);
PAINT MONO (-4202 1400);
FORCEPROP 2 LAST PATH I116
J 0
(-4200 1450);
DISPLAY 1.021277 (-4200 1450);
DISPLAY INVISIBLE (-4200 1450);
FORCEPROP 1 LAST OFFPAGE TRUE
J 0
(-3625 1275);
DISPLAY 0.872340 (-3625 1275);
DISPLAY INVISIBLE (-3625 1275);
FORCEPROP 1 LAST COMMENT_BODY TRUE
J 0
(-3825 1300);
DISPLAY 1.170213 (-3825 1300);
PAINT GREEN (-3825 1300);
DISPLAY INVISIBLE (-3825 1300);
FORCEPROP 2 LAST CDS_LIB standard
J 0
(-3950 1400);
DISPLAY INVISIBLE (-3950 1400);
FORCEADD OFFPAGE..2
(-3175 -600);
FORCEPROP 2 LAST $XR0 215 
J 0
(-2986 -600);
DISPLAY 0.638298 (-2986 -600);
PAINT MONO (-2986 -600);
FORCEPROP 2 LAST PATH I117
J 0
(-2975 -550);
DISPLAY 1.021277 (-2975 -550);
DISPLAY INVISIBLE (-2975 -550);
FORCEPROP 1 LAST OFFPAGE TRUE
J 0
(-2850 -725);
DISPLAY 0.872340 (-2850 -725);
PAINT GREEN (-2850 -725);
DISPLAY INVISIBLE (-2850 -725);
FORCEPROP 1 LAST COMMENT_BODY TRUE
J 0
(-3220 -695);
DISPLAY 0.872340 (-3220 -695);
PAINT PEACH (-3220 -695);
DISPLAY INVISIBLE (-3220 -695);
FORCEPROP 2 LAST CDS_LIB standard
J 0
(-3175 -600);
DISPLAY INVISIBLE (-3175 -600);
FORCEADD OFFPAGE..2
(-3175 -775);
FORCEPROP 2 LAST $XR0 215 
J 0
(-2986 -775);
DISPLAY 0.638298 (-2986 -775);
PAINT MONO (-2986 -775);
FORCEPROP 2 LAST PATH I118
J 0
(-2975 -725);
DISPLAY 1.021277 (-2975 -725);
DISPLAY INVISIBLE (-2975 -725);
FORCEPROP 2 LAST CDS_LIB standard
J 0
(-3175 -775);
DISPLAY INVISIBLE (-3175 -775);
FORCEPROP 1 LAST COMMENT_BODY TRUE
J 0
(-3220 -870);
DISPLAY 0.872340 (-3220 -870);
PAINT PEACH (-3220 -870);
DISPLAY INVISIBLE (-3220 -870);
FORCEPROP 1 LAST OFFPAGE TRUE
J 0
(-2850 -900);
DISPLAY 0.872340 (-2850 -900);
PAINT GREEN (-2850 -900);
DISPLAY INVISIBLE (-2850 -900);
FORCEADD OFFPAGE..2
(-3175 -950);
FORCEPROP 2 LAST $XR0 215 
J 0
(-2986 -950);
DISPLAY 0.638298 (-2986 -950);
PAINT MONO (-2986 -950);
FORCEPROP 2 LAST PATH I119
J 0
(-2975 -900);
DISPLAY 1.021277 (-2975 -900);
DISPLAY INVISIBLE (-2975 -900);
FORCEPROP 1 LAST OFFPAGE TRUE
J 0
(-2850 -1075);
DISPLAY 0.872340 (-2850 -1075);
PAINT GREEN (-2850 -1075);
DISPLAY INVISIBLE (-2850 -1075);
FORCEPROP 1 LAST COMMENT_BODY TRUE
J 0
(-3220 -1045);
DISPLAY 0.872340 (-3220 -1045);
PAINT PEACH (-3220 -1045);
DISPLAY INVISIBLE (-3220 -1045);
FORCEPROP 2 LAST CDS_LIB standard
J 0
(-3175 -950);
DISPLAY INVISIBLE (-3175 -950);
FORCEADD OFFPAGE..2
(-75 3300);
FORCEPROP 2 LAST $XR0 215 
J 0
(114 3300);
DISPLAY 0.638298 (114 3300);
PAINT MONO (114 3300);
FORCEPROP 2 LAST PATH I12
J 0
(125 3350);
DISPLAY 1.021277 (125 3350);
DISPLAY INVISIBLE (125 3350);
FORCEPROP 2 LAST CDS_LIB standard
J 0
(-75 3300);
DISPLAY INVISIBLE (-75 3300);
FORCEPROP 1 LAST COMMENT_BODY TRUE
J 0
(-120 3205);
DISPLAY 1.170213 (-120 3205);
PAINT GREEN (-120 3205);
DISPLAY INVISIBLE (-120 3205);
FORCEPROP 1 LAST OFFPAGE TRUE
J 0
(250 3175);
DISPLAY 1.170213 (250 3175);
PAINT GREEN (250 3175);
DISPLAY INVISIBLE (250 3175);
FORCEADD Q_RES..1
(-4550 -600);
FORCEPROP 1 LAST PART_NUMBER CS03322FB03
J 0
(-4700 -525);
DISPLAY 0.638298 (-4700 -525);
DISPLAY INVISIBLE (-4700 -525);
FORCEPROP 1 LAST TOLERANCE 1%
J 0
(-4275 -600);
DISPLAY 0.638298 (-4275 -600);
FORCEPROP 1 LAST VALUE 33.2
J 2
(-4300 -600);
DISPLAY 0.638298 (-4300 -600);
FORCEPROP 1 LAST MATERIAL CHIP
J 0
(-4200 -600);
DISPLAY 0.638298 (-4200 -600);
FORCEPROP 1 LAST $LOCATION R4170
J 0
(-4825 -600);
DISPLAY 0.787234 (-4825 -600);
FORCEPROP 1 LASTPIN (-4650 -600) $PN 1
J 0
(-4638 -588);
DISPLAY 0.787234 (-4638 -588);
FORCEPROP 1 LASTPIN (-4450 -600) $PN 2
J 0
(-4488 -588);
DISPLAY 0.787234 (-4488 -588);
FORCEPROP 1 LAST WATTAGE 1/16W
J 2
(-4350 -475);
DISPLAY 0.638298 (-4350 -475);
DISPLAY INVISIBLE (-4350 -475);
FORCEPROP 1 LAST PACK_TYPE 0402LF
J 0
(-4700 -475);
DISPLAY 0.638298 (-4700 -475);
DISPLAY INVISIBLE (-4700 -475);
FORCEPROP 2 LAST CDS_LIB pure_quanta
J 0
(-4550 -600);
PAINT MONO (-4550 -600);
DISPLAY INVISIBLE (-4550 -600);
FORCEPROP 1 LAST PATH I120
J 0
(-4600 -450);
DISPLAY 0.978723 (-4600 -450);
PAINT WHITE (-4600 -450);
DISPLAY INVISIBLE (-4600 -450);
FORCEPROP 2 LAST CDS_LOCATION R4170
J 0
(-4600 -400);
DISPLAY 1.021277 (-4600 -400);
DISPLAY INVISIBLE (-4600 -400);
FORCEPROP 2 LAST $SEC 1
J 0
(-4600 -400);
DISPLAY 0.680851 (-4600 -400);
PAINT MONO (-4600 -400);
DISPLAY INVISIBLE (-4600 -400);
FORCEPROP 2 LAST CDS_SEC 1
J 0
(-4600 -400);
DISPLAY 1.021277 (-4600 -400);
DISPLAY INVISIBLE (-4600 -400);
FORCEADD Q_RES..1
(-4550 -775);
FORCEPROP 1 LAST PART_NUMBER CS03322FB03
J 0
(-4700 -700);
DISPLAY 0.638298 (-4700 -700);
DISPLAY INVISIBLE (-4700 -700);
FORCEPROP 1 LAST TOLERANCE 1%
J 0
(-4275 -775);
DISPLAY 0.638298 (-4275 -775);
FORCEPROP 1 LAST VALUE 33.2
J 2
(-4300 -775);
DISPLAY 0.638298 (-4300 -775);
FORCEPROP 1 LAST MATERIAL CHIP
J 0
(-4200 -775);
DISPLAY 0.638298 (-4200 -775);
FORCEPROP 1 LAST $LOCATION R4171
J 0
(-4825 -775);
DISPLAY 0.787234 (-4825 -775);
FORCEPROP 1 LASTPIN (-4650 -775) $PN 1
J 0
(-4638 -763);
DISPLAY 0.787234 (-4638 -763);
FORCEPROP 1 LASTPIN (-4450 -775) $PN 2
J 0
(-4488 -763);
DISPLAY 0.787234 (-4488 -763);
FORCEPROP 2 LAST CDS_LIB pure_quanta
J 0
(-4550 -775);
PAINT MONO (-4550 -775);
DISPLAY INVISIBLE (-4550 -775);
FORCEPROP 1 LAST PACK_TYPE 0402LF
J 0
(-4700 -650);
DISPLAY 0.638298 (-4700 -650);
DISPLAY INVISIBLE (-4700 -650);
FORCEPROP 1 LAST WATTAGE 1/16W
J 2
(-4350 -650);
DISPLAY 0.638298 (-4350 -650);
DISPLAY INVISIBLE (-4350 -650);
FORCEPROP 1 LAST PATH I121
J 0
(-4600 -625);
DISPLAY 0.978723 (-4600 -625);
PAINT WHITE (-4600 -625);
DISPLAY INVISIBLE (-4600 -625);
FORCEPROP 2 LAST CDS_LOCATION R4171
J 0
(-4600 -575);
DISPLAY 1.021277 (-4600 -575);
DISPLAY INVISIBLE (-4600 -575);
FORCEPROP 2 LAST $SEC 1
J 0
(-4600 -575);
DISPLAY 0.680851 (-4600 -575);
PAINT MONO (-4600 -575);
DISPLAY INVISIBLE (-4600 -575);
FORCEPROP 2 LAST CDS_SEC 1
J 0
(-4600 -575);
DISPLAY 1.021277 (-4600 -575);
DISPLAY INVISIBLE (-4600 -575);
FORCEADD Q_RES..1
(-4550 -950);
FORCEPROP 1 LAST PART_NUMBER CS03322FB03
J 0
(-4700 -875);
DISPLAY 0.638298 (-4700 -875);
DISPLAY INVISIBLE (-4700 -875);
FORCEPROP 1 LAST TOLERANCE 1%
J 0
(-4275 -950);
DISPLAY 0.638298 (-4275 -950);
FORCEPROP 1 LAST MATERIAL CHIP
J 0
(-4200 -950);
DISPLAY 0.638298 (-4200 -950);
FORCEPROP 1 LAST VALUE 33.2
J 2
(-4300 -950);
DISPLAY 0.638298 (-4300 -950);
FORCEPROP 1 LAST $LOCATION R4172
J 0
(-4825 -950);
DISPLAY 0.787234 (-4825 -950);
FORCEPROP 1 LASTPIN (-4650 -950) $PN 1
J 0
(-4638 -938);
DISPLAY 0.787234 (-4638 -938);
FORCEPROP 1 LASTPIN (-4450 -950) $PN 2
J 0
(-4488 -938);
DISPLAY 0.787234 (-4488 -938);
FORCEPROP 1 LAST WATTAGE 1/16W
J 2
(-4350 -825);
DISPLAY 0.638298 (-4350 -825);
DISPLAY INVISIBLE (-4350 -825);
FORCEPROP 1 LAST PACK_TYPE 0402LF
J 0
(-4700 -825);
DISPLAY 0.638298 (-4700 -825);
DISPLAY INVISIBLE (-4700 -825);
FORCEPROP 1 LAST PATH I122
J 0
(-4600 -800);
DISPLAY 0.978723 (-4600 -800);
PAINT WHITE (-4600 -800);
DISPLAY INVISIBLE (-4600 -800);
FORCEPROP 2 LAST CDS_LIB pure_quanta
J 0
(-4550 -950);
PAINT MONO (-4550 -950);
DISPLAY INVISIBLE (-4550 -950);
FORCEPROP 2 LAST CDS_LOCATION R4172
J 0
(-4600 -750);
DISPLAY 1.021277 (-4600 -750);
DISPLAY INVISIBLE (-4600 -750);
FORCEPROP 2 LAST $SEC 1
J 0
(-4600 -750);
DISPLAY 0.680851 (-4600 -750);
PAINT MONO (-4600 -750);
DISPLAY INVISIBLE (-4600 -750);
FORCEPROP 2 LAST CDS_SEC 1
J 0
(-4600 -750);
DISPLAY 1.021277 (-4600 -750);
DISPLAY INVISIBLE (-4600 -750);
FORCEADD OFFPAGE..1
(-5775 -600);
FORCEPROP 2 LAST $XR0 145 
J 0
(-6027 -600);
DISPLAY 0.638298 (-6027 -600);
PAINT MONO (-6027 -600);
FORCEPROP 2 LAST PATH I123
J 0
(-6025 -550);
DISPLAY 1.021277 (-6025 -550);
DISPLAY INVISIBLE (-6025 -550);
FORCEPROP 1 LAST OFFPAGE TRUE
J 0
(-5450 -725);
DISPLAY 0.872340 (-5450 -725);
DISPLAY INVISIBLE (-5450 -725);
FORCEPROP 1 LAST COMMENT_BODY TRUE
J 0
(-5650 -700);
DISPLAY 1.170213 (-5650 -700);
PAINT GREEN (-5650 -700);
DISPLAY INVISIBLE (-5650 -700);
FORCEPROP 2 LAST CDS_LIB standard
J 0
(-5775 -600);
DISPLAY INVISIBLE (-5775 -600);
FORCEADD OFFPAGE..1
(-5775 -775);
FORCEPROP 2 LAST $XR0 145 
J 0
(-6027 -775);
DISPLAY 0.638298 (-6027 -775);
PAINT MONO (-6027 -775);
FORCEPROP 2 LAST PATH I124
J 0
(-6025 -725);
DISPLAY 1.021277 (-6025 -725);
DISPLAY INVISIBLE (-6025 -725);
FORCEPROP 2 LAST CDS_LIB standard
J 0
(-5775 -775);
DISPLAY INVISIBLE (-5775 -775);
FORCEPROP 1 LAST COMMENT_BODY TRUE
J 0
(-5650 -875);
DISPLAY 1.170213 (-5650 -875);
PAINT GREEN (-5650 -875);
DISPLAY INVISIBLE (-5650 -875);
FORCEPROP 1 LAST OFFPAGE TRUE
J 0
(-5450 -900);
DISPLAY 0.872340 (-5450 -900);
DISPLAY INVISIBLE (-5450 -900);
FORCEADD OFFPAGE..1
(-5775 -950);
FORCEPROP 2 LAST $XR0 145 
J 0
(-6027 -950);
DISPLAY 0.638298 (-6027 -950);
PAINT MONO (-6027 -950);
FORCEPROP 2 LAST PATH I125
J 0
(-6025 -900);
DISPLAY 1.021277 (-6025 -900);
DISPLAY INVISIBLE (-6025 -900);
FORCEPROP 1 LAST OFFPAGE TRUE
J 0
(-5450 -1075);
DISPLAY 0.872340 (-5450 -1075);
DISPLAY INVISIBLE (-5450 -1075);
FORCEPROP 1 LAST COMMENT_BODY TRUE
J 0
(-5650 -1050);
DISPLAY 1.170213 (-5650 -1050);
PAINT GREEN (-5650 -1050);
DISPLAY INVISIBLE (-5650 -1050);
FORCEPROP 2 LAST CDS_LIB standard
J 0
(-5775 -950);
DISPLAY INVISIBLE (-5775 -950);
FORCEADD OFFPAGE..1
(-3950 1300);
FORCEPROP 2 LAST $XR0 215 
J 0
(-4202 1300);
DISPLAY 0.638298 (-4202 1300);
PAINT MONO (-4202 1300);
FORCEPROP 1 LAST OFFPAGE TRUE
J 0
(-3625 1175);
DISPLAY 0.872340 (-3625 1175);
DISPLAY INVISIBLE (-3625 1175);
FORCEPROP 1 LAST COMMENT_BODY TRUE
J 0
(-3825 1200);
DISPLAY 1.170213 (-3825 1200);
PAINT GREEN (-3825 1200);
DISPLAY INVISIBLE (-3825 1200);
FORCEPROP 2 LAST CDS_LIB standard
J 0
(-3950 1300);
DISPLAY INVISIBLE (-3950 1300);
FORCEPROP 2 LAST PATH I126
J 0
(-4200 1350);
DISPLAY 1.021277 (-4200 1350);
DISPLAY INVISIBLE (-4200 1350);
FORCEADD OFFPAGE..1
(-3950 1350);
FORCEPROP 2 LAST $XR0 215 
J 0
(-4202 1350);
DISPLAY 0.638298 (-4202 1350);
PAINT MONO (-4202 1350);
FORCEPROP 2 LAST CDS_LIB standard
J 0
(-3950 1350);
DISPLAY INVISIBLE (-3950 1350);
FORCEPROP 1 LAST COMMENT_BODY TRUE
J 0
(-3825 1250);
DISPLAY 1.170213 (-3825 1250);
PAINT GREEN (-3825 1250);
DISPLAY INVISIBLE (-3825 1250);
FORCEPROP 1 LAST OFFPAGE TRUE
J 0
(-3625 1225);
DISPLAY 0.872340 (-3625 1225);
DISPLAY INVISIBLE (-3625 1225);
FORCEPROP 2 LAST PATH I127
J 0
(-4200 1400);
DISPLAY 1.021277 (-4200 1400);
DISPLAY INVISIBLE (-4200 1400);
FORCEADD OFFPAGE..1
(-3950 1250);
FORCEPROP 2 LAST $XR0 215 
J 0
(-4202 1250);
DISPLAY 0.638298 (-4202 1250);
PAINT MONO (-4202 1250);
FORCEPROP 2 LAST CDS_LIB standard
J 0
(-3950 1250);
DISPLAY INVISIBLE (-3950 1250);
FORCEPROP 1 LAST COMMENT_BODY TRUE
J 0
(-3825 1150);
DISPLAY 1.170213 (-3825 1150);
PAINT GREEN (-3825 1150);
DISPLAY INVISIBLE (-3825 1150);
FORCEPROP 1 LAST OFFPAGE TRUE
J 0
(-3625 1125);
DISPLAY 0.872340 (-3625 1125);
DISPLAY INVISIBLE (-3625 1125);
FORCEPROP 2 LAST PATH I128
J 0
(-4200 1300);
DISPLAY 1.021277 (-4200 1300);
DISPLAY INVISIBLE (-4200 1300);
FORCEADD OFFPAGE..1
(-1850 875);
FORCEPROP 2 LAST $XR1 219 
J 0
(-2222 875);
DISPLAY 0.638298 (-2222 875);
PAINT MONO (-2222 875);
FORCEPROP 2 LAST $XR0 215 
J 0
(-2102 875);
DISPLAY 0.638298 (-2102 875);
PAINT MONO (-2102 875);
FORCEPROP 1 LAST OFFPAGE TRUE
J 0
(-1525 750);
DISPLAY 0.872340 (-1525 750);
DISPLAY INVISIBLE (-1525 750);
FORCEPROP 1 LAST COMMENT_BODY TRUE
J 0
(-1725 775);
DISPLAY 1.170213 (-1725 775);
PAINT GREEN (-1725 775);
DISPLAY INVISIBLE (-1725 775);
FORCEPROP 2 LAST CDS_LIB standard
J 0
(-1850 875);
DISPLAY INVISIBLE (-1850 875);
FORCEPROP 2 LAST PATH I129
J 0
(-2125 925);
DISPLAY 1.021277 (-2125 925);
DISPLAY INVISIBLE (-2125 925);
FORCEADD OFFPAGE..1
R 2
(-75 3250);
FORCEPROP 2 LAST $XR0 222 
J 0
(111 3250);
DISPLAY 0.638298 (111 3250);
PAINT MONO (111 3250);
FORCEPROP 2 LAST PATH I13
J 0
(125 3300);
DISPLAY 1.021277 (125 3300);
DISPLAY INVISIBLE (125 3300);
FORCEPROP 1 LAST OFFPAGE TRUE
J 2
(-400 3125);
DISPLAY 1.170213 (-400 3125);
PAINT GREEN (-400 3125);
DISPLAY INVISIBLE (-400 3125);
FORCEPROP 1 LAST COMMENT_BODY TRUE
J 2
(-200 3150);
DISPLAY 1.170213 (-200 3150);
PAINT GREEN (-200 3150);
DISPLAY INVISIBLE (-200 3150);
FORCEPROP 2 LAST CDS_LIB standard
J 0
(-75 3250);
DISPLAY INVISIBLE (-75 3250);
FORCEADD OFFPAGE..2
(950 875);
FORCEPROP 2 LAST $XR0 191 
J 0
(1139 875);
DISPLAY 0.638298 (1139 875);
PAINT MONO (1139 875);
FORCEPROP 2 LAST CDS_LIB standard
J 0
(950 875);
PAINT MONO (950 875);
DISPLAY INVISIBLE (950 875);
FORCEPROP 1 LAST OFFPAGE TRUE
J 0
(1275 750);
DISPLAY 0.872340 (1275 750);
PAINT GREEN (1275 750);
DISPLAY INVISIBLE (1275 750);
FORCEPROP 1 LAST COMMENT_BODY TRUE
J 0
(905 780);
DISPLAY 0.872340 (905 780);
PAINT PEACH (905 780);
DISPLAY INVISIBLE (905 780);
FORCEPROP 2 LAST PATH I132
J 0
(1150 925);
DISPLAY 1.021277 (1150 925);
DISPLAY INVISIBLE (1150 925);
FORCEADD OFFPAGE..2
(950 700);
FORCEPROP 2 LAST $XR0 190 
J 0
(1139 700);
DISPLAY 0.638298 (1139 700);
PAINT MONO (1139 700);
FORCEPROP 1 LAST COMMENT_BODY TRUE
J 0
(905 605);
DISPLAY 0.872340 (905 605);
PAINT PEACH (905 605);
DISPLAY INVISIBLE (905 605);
FORCEPROP 1 LAST OFFPAGE TRUE
J 0
(1275 575);
DISPLAY 0.872340 (1275 575);
PAINT GREEN (1275 575);
DISPLAY INVISIBLE (1275 575);
FORCEPROP 2 LAST CDS_LIB standard
J 0
(950 700);
DISPLAY INVISIBLE (950 700);
FORCEPROP 2 LAST PATH I133
J 0
(1150 750);
DISPLAY 1.021277 (1150 750);
DISPLAY INVISIBLE (1150 750);
FORCEADD Q_RES..1
(-575 875);
FORCEPROP 1 LAST PART_NUMBER CS03322FB03
J 0
(-725 950);
DISPLAY 0.638298 (-725 950);
DISPLAY INVISIBLE (-725 950);
FORCEPROP 1 LAST VALUE 33.2
J 2
(-325 875);
DISPLAY 0.638298 (-325 875);
FORCEPROP 1 LAST TOLERANCE 1%
J 0
(-300 875);
DISPLAY 0.638298 (-300 875);
FORCEPROP 1 LAST MATERIAL CHIP
J 0
(-225 875);
DISPLAY 0.638298 (-225 875);
FORCEPROP 1 LAST $LOCATION R4174
J 0
(-775 875);
DISPLAY 0.638298 (-775 875);
FORCEPROP 1 LASTPIN (-675 875) $PN 1
J 0
(-663 887);
DISPLAY 0.787234 (-663 887);
PAINT MONO (-663 887);
FORCEPROP 1 LASTPIN (-475 875) $PN 2
J 0
(-513 887);
DISPLAY 0.787234 (-513 887);
PAINT MONO (-513 887);
FORCEPROP 2 LAST CDS_LIB pure_quanta
J 0
(-575 875);
DISPLAY INVISIBLE (-575 875);
FORCEPROP 1 LAST PATH I134
J 0
(-625 1025);
DISPLAY 0.978723 (-625 1025);
PAINT WHITE (-625 1025);
DISPLAY INVISIBLE (-625 1025);
FORCEPROP 1 LAST PACK_TYPE 0402LF
J 0
(-725 1000);
DISPLAY 0.638298 (-725 1000);
DISPLAY INVISIBLE (-725 1000);
FORCEPROP 1 LAST WATTAGE 1/16W
J 2
(-375 1000);
DISPLAY 0.638298 (-375 1000);
DISPLAY INVISIBLE (-375 1000);
FORCEPROP 0 LAST CDS_LOCATION R4174
J 0
(-225 925);
DISPLAY 1.021277 (-225 925);
DISPLAY INVISIBLE (-225 925);
FORCEPROP 0 LAST $SEC 1
J 0
(-225 925);
DISPLAY 0.680851 (-225 925);
PAINT MONO (-225 925);
DISPLAY INVISIBLE (-225 925);
FORCEPROP 0 LAST CDS_SEC 1
J 0
(-225 925);
DISPLAY 1.021277 (-225 925);
DISPLAY INVISIBLE (-225 925);
FORCEADD Q_RES..1
(-575 700);
FORCEPROP 1 LAST PART_NUMBER CS03322FB03
J 0
(-725 775);
DISPLAY 0.638298 (-725 775);
DISPLAY INVISIBLE (-725 775);
FORCEPROP 1 LAST VALUE 33.2
J 2
(-325 700);
DISPLAY 0.638298 (-325 700);
FORCEPROP 1 LAST MATERIAL CHIP
J 0
(-225 700);
DISPLAY 0.638298 (-225 700);
FORCEPROP 1 LAST TOLERANCE 1%
J 0
(-300 700);
DISPLAY 0.638298 (-300 700);
FORCEPROP 1 LAST $LOCATION R4175
J 0
(-775 700);
DISPLAY 0.638298 (-775 700);
FORCEPROP 1 LASTPIN (-675 700) $PN 1
J 0
(-663 712);
DISPLAY 0.787234 (-663 712);
PAINT MONO (-663 712);
FORCEPROP 1 LASTPIN (-475 700) $PN 2
J 0
(-513 712);
DISPLAY 0.787234 (-513 712);
PAINT MONO (-513 712);
FORCEPROP 1 LAST WATTAGE 1/16W
J 2
(-375 825);
DISPLAY 0.638298 (-375 825);
DISPLAY INVISIBLE (-375 825);
FORCEPROP 1 LAST PACK_TYPE 0402LF
J 0
(-725 825);
DISPLAY 0.638298 (-725 825);
DISPLAY INVISIBLE (-725 825);
FORCEPROP 1 LAST PATH I135
J 0
(-625 850);
DISPLAY 0.978723 (-625 850);
PAINT WHITE (-625 850);
DISPLAY INVISIBLE (-625 850);
FORCEPROP 2 LAST CDS_LIB pure_quanta
J 0
(-575 700);
DISPLAY INVISIBLE (-575 700);
FORCEPROP 0 LAST CDS_LOCATION R4175
J 0
(-225 750);
DISPLAY 1.021277 (-225 750);
DISPLAY INVISIBLE (-225 750);
FORCEPROP 0 LAST $SEC 1
J 0
(-225 750);
DISPLAY 0.680851 (-225 750);
PAINT MONO (-225 750);
DISPLAY INVISIBLE (-225 750);
FORCEPROP 0 LAST CDS_SEC 1
J 0
(-225 750);
DISPLAY 1.021277 (-225 750);
DISPLAY INVISIBLE (-225 750);
FORCEADD OFFPAGE..2
(-75 2150);
FORCEPROP 2 LAST $XR0 211 
J 0
(114 2150);
DISPLAY 0.638298 (114 2150);
PAINT MONO (114 2150);
FORCEPROP 2 LAST CDS_LIB standard
J 0
(-75 2150);
DISPLAY INVISIBLE (-75 2150);
FORCEPROP 2 LAST PATH I136
J 0
(100 2225);
DISPLAY 1.021277 (100 2225);
DISPLAY INVISIBLE (100 2225);
FORCEPROP 1 LAST OFFPAGE TRUE
J 0
(250 2025);
DISPLAY 1.170213 (250 2025);
PAINT GREEN (250 2025);
DISPLAY INVISIBLE (250 2025);
FORCEPROP 1 LAST COMMENT_BODY TRUE
J 0
(-120 2055);
DISPLAY 1.170213 (-120 2055);
PAINT GREEN (-120 2055);
DISPLAY INVISIBLE (-120 2055);
FORCEADD OFFPAGE..2
(-75 2200);
FORCEPROP 2 LAST $XR0 211 
J 0
(114 2200);
DISPLAY 0.638298 (114 2200);
PAINT MONO (114 2200);
FORCEPROP 2 LAST CDS_LIB standard
J 0
(-75 2200);
DISPLAY INVISIBLE (-75 2200);
FORCEPROP 2 LAST PATH I137
J 0
(100 2275);
DISPLAY 1.021277 (100 2275);
DISPLAY INVISIBLE (100 2275);
FORCEPROP 1 LAST OFFPAGE TRUE
J 0
(250 2075);
DISPLAY 1.170213 (250 2075);
PAINT GREEN (250 2075);
DISPLAY INVISIBLE (250 2075);
FORCEPROP 1 LAST COMMENT_BODY TRUE
J 0
(-120 2105);
DISPLAY 1.170213 (-120 2105);
PAINT GREEN (-120 2105);
DISPLAY INVISIBLE (-120 2105);
FORCEADD OFFPAGE..2
(-75 1950);
FORCEPROP 2 LAST $XR0 211 
J 0
(114 1950);
DISPLAY 0.638298 (114 1950);
PAINT MONO (114 1950);
FORCEPROP 1 LAST OFFPAGE TRUE
J 0
(250 1825);
DISPLAY 1.170213 (250 1825);
PAINT GREEN (250 1825);
DISPLAY INVISIBLE (250 1825);
FORCEPROP 1 LAST COMMENT_BODY TRUE
J 0
(-120 1855);
DISPLAY 1.170213 (-120 1855);
PAINT GREEN (-120 1855);
DISPLAY INVISIBLE (-120 1855);
FORCEPROP 2 LAST PATH I138
J 0
(100 2025);
DISPLAY 1.021277 (100 2025);
DISPLAY INVISIBLE (100 2025);
FORCEPROP 2 LAST CDS_LIB standard
J 0
(-75 1950);
DISPLAY INVISIBLE (-75 1950);
FORCEADD OFFPAGE..1
R 2
(-75 3200);
FORCEPROP 2 LAST $XR1 204 
J 0
(231 3200);
DISPLAY 0.638298 (231 3200);
PAINT MONO (231 3200);
FORCEPROP 2 LAST $XR0 184 
J 0
(111 3200);
DISPLAY 0.638298 (111 3200);
PAINT MONO (111 3200);
FORCEPROP 2 LAST PATH I14
J 0
(250 3250);
DISPLAY 1.021277 (250 3250);
DISPLAY INVISIBLE (250 3250);
FORCEPROP 1 LAST COMMENT_BODY TRUE
J 2
(-200 3100);
DISPLAY 1.170213 (-200 3100);
PAINT GREEN (-200 3100);
DISPLAY INVISIBLE (-200 3100);
FORCEPROP 1 LAST OFFPAGE TRUE
J 2
(-400 3075);
DISPLAY 1.170213 (-400 3075);
PAINT GREEN (-400 3075);
DISPLAY INVISIBLE (-400 3075);
FORCEPROP 2 LAST CDS_LIB standard
J 0
(-75 3200);
DISPLAY INVISIBLE (-75 3200);
FORCEADD OFFPAGE..2
(950 525);
FORCEPROP 2 LAST $XR0 145 
J 0
(1139 525);
DISPLAY 0.638298 (1139 525);
PAINT MONO (1139 525);
FORCEPROP 2 LAST PATH I140
J 0
(1150 575);
DISPLAY 1.021277 (1150 575);
DISPLAY INVISIBLE (1150 575);
FORCEPROP 2 LAST CDS_LIB standard
J 0
(950 525);
PAINT MONO (950 525);
DISPLAY INVISIBLE (950 525);
FORCEPROP 1 LAST OFFPAGE TRUE
J 0
(1275 400);
DISPLAY 0.872340 (1275 400);
PAINT GREEN (1275 400);
DISPLAY INVISIBLE (1275 400);
FORCEPROP 1 LAST COMMENT_BODY TRUE
J 0
(905 430);
DISPLAY 0.872340 (905 430);
PAINT PEACH (905 430);
DISPLAY INVISIBLE (905 430);
FORCEADD OFFPAGE..1
(-1925 525);
FORCEPROP 2 LAST $XR0 215 
J 0
(-2177 525);
DISPLAY 0.638298 (-2177 525);
PAINT MONO (-2177 525);
FORCEPROP 2 LAST CDS_LIB standard
J 0
(-1925 525);
DISPLAY INVISIBLE (-1925 525);
FORCEPROP 1 LAST OFFPAGE TRUE
J 0
(-1600 400);
DISPLAY 0.872340 (-1600 400);
DISPLAY INVISIBLE (-1600 400);
FORCEPROP 1 LAST COMMENT_BODY TRUE
J 0
(-1800 425);
DISPLAY 1.170213 (-1800 425);
PAINT GREEN (-1800 425);
DISPLAY INVISIBLE (-1800 425);
FORCEPROP 2 LAST PATH I142
J 0
(-2175 575);
DISPLAY 1.021277 (-2175 575);
DISPLAY INVISIBLE (-2175 575);
FORCEADD Q_RES..1
(-575 525);
FORCEPROP 1 LAST PART_NUMBER CS03322FB03
J 0
(-725 600);
DISPLAY 0.638298 (-725 600);
DISPLAY INVISIBLE (-725 600);
FORCEPROP 1 LAST VALUE 33.2
J 2
(-325 525);
DISPLAY 0.638298 (-325 525);
FORCEPROP 1 LAST MATERIAL CHIP
J 0
(-225 525);
DISPLAY 0.638298 (-225 525);
FORCEPROP 1 LAST TOLERANCE 1%
J 0
(-300 525);
DISPLAY 0.638298 (-300 525);
FORCEPROP 1 LAST $LOCATION R4556
J 0
(-775 525);
DISPLAY 0.638298 (-775 525);
FORCEPROP 1 LASTPIN (-675 525) $PN 1
J 0
(-663 537);
DISPLAY 0.787234 (-663 537);
PAINT MONO (-663 537);
FORCEPROP 1 LASTPIN (-475 525) $PN 2
J 0
(-513 537);
DISPLAY 0.787234 (-513 537);
PAINT MONO (-513 537);
FORCEPROP 2 LAST CDS_LIB pure_quanta
J 0
(-575 525);
DISPLAY INVISIBLE (-575 525);
FORCEPROP 1 LAST WATTAGE 1/16W
J 2
(-375 650);
DISPLAY 0.638298 (-375 650);
DISPLAY INVISIBLE (-375 650);
FORCEPROP 1 LAST PACK_TYPE 0402LF
J 0
(-725 650);
DISPLAY 0.638298 (-725 650);
DISPLAY INVISIBLE (-725 650);
FORCEPROP 1 LAST PATH I143
J 0
(-625 675);
DISPLAY 0.978723 (-625 675);
PAINT WHITE (-625 675);
DISPLAY INVISIBLE (-625 675);
FORCEPROP 0 LAST CDS_LOCATION R4556
J 0
(-225 575);
DISPLAY 1.021277 (-225 575);
DISPLAY INVISIBLE (-225 575);
FORCEPROP 0 LAST $SEC 1
J 0
(-225 575);
DISPLAY 0.680851 (-225 575);
PAINT MONO (-225 575);
DISPLAY INVISIBLE (-225 575);
FORCEPROP 0 LAST CDS_SEC 1
J 0
(-225 575);
DISPLAY 1.021277 (-225 575);
DISPLAY INVISIBLE (-225 575);
FORCEADD OFFPAGE..2
(950 350);
FORCEPROP 2 LAST $XR0 215 
J 0
(1139 350);
DISPLAY 0.638298 (1139 350);
PAINT MONO (1139 350);
FORCEPROP 2 LAST CDS_LIB standard
J 0
(950 350);
PAINT MONO (950 350);
DISPLAY INVISIBLE (950 350);
FORCEPROP 2 LAST PATH I144
J 0
(1150 400);
DISPLAY 1.021277 (1150 400);
DISPLAY INVISIBLE (1150 400);
FORCEPROP 1 LAST OFFPAGE TRUE
J 0
(1275 225);
DISPLAY 0.872340 (1275 225);
PAINT GREEN (1275 225);
DISPLAY INVISIBLE (1275 225);
FORCEPROP 1 LAST COMMENT_BODY TRUE
J 0
(905 255);
DISPLAY 0.872340 (905 255);
PAINT PEACH (905 255);
DISPLAY INVISIBLE (905 255);
FORCEADD Q_RES..1
(-575 350);
FORCEPROP 1 LAST PART_NUMBER CS03322FB03
J 0
(-725 425);
DISPLAY 0.638298 (-725 425);
DISPLAY INVISIBLE (-725 425);
FORCEPROP 1 LAST VALUE 33.2
J 2
(-325 350);
DISPLAY 0.638298 (-325 350);
FORCEPROP 1 LAST MATERIAL CHIP
J 0
(-225 350);
DISPLAY 0.638298 (-225 350);
FORCEPROP 1 LAST TOLERANCE 1%
J 0
(-300 350);
DISPLAY 0.638298 (-300 350);
FORCEPROP 1 LAST $LOCATION R4557
J 0
(-775 350);
DISPLAY 0.638298 (-775 350);
FORCEPROP 1 LASTPIN (-675 350) $PN 1
J 0
(-663 362);
DISPLAY 0.787234 (-663 362);
PAINT MONO (-663 362);
FORCEPROP 1 LASTPIN (-475 350) $PN 2
J 0
(-513 362);
DISPLAY 0.787234 (-513 362);
PAINT MONO (-513 362);
FORCEPROP 2 LAST CDS_LIB pure_quanta
J 0
(-575 350);
DISPLAY INVISIBLE (-575 350);
FORCEPROP 1 LAST WATTAGE 1/16W
J 2
(-375 475);
DISPLAY 0.638298 (-375 475);
DISPLAY INVISIBLE (-375 475);
FORCEPROP 1 LAST PACK_TYPE 0402LF
J 0
(-725 475);
DISPLAY 0.638298 (-725 475);
DISPLAY INVISIBLE (-725 475);
FORCEPROP 1 LAST PATH I145
J 0
(-625 500);
DISPLAY 0.978723 (-625 500);
PAINT WHITE (-625 500);
DISPLAY INVISIBLE (-625 500);
FORCEPROP 0 LAST CDS_LOCATION R4557
J 0
(-225 400);
DISPLAY 1.021277 (-225 400);
DISPLAY INVISIBLE (-225 400);
FORCEPROP 0 LAST $SEC 1
J 0
(-225 400);
DISPLAY 0.680851 (-225 400);
PAINT MONO (-225 400);
DISPLAY INVISIBLE (-225 400);
FORCEPROP 0 LAST CDS_SEC 1
J 0
(-225 400);
DISPLAY 1.021277 (-225 400);
DISPLAY INVISIBLE (-225 400);
FORCEADD OFFPAGE..1
(-1925 350);
FORCEPROP 2 LAST $XR0 246 
J 0
(-2177 350);
DISPLAY 0.638298 (-2177 350);
PAINT MONO (-2177 350);
FORCEPROP 1 LAST OFFPAGE TRUE
J 0
(-1600 225);
DISPLAY 0.872340 (-1600 225);
DISPLAY INVISIBLE (-1600 225);
FORCEPROP 1 LAST COMMENT_BODY TRUE
J 0
(-1800 250);
DISPLAY 1.170213 (-1800 250);
PAINT GREEN (-1800 250);
DISPLAY INVISIBLE (-1800 250);
FORCEPROP 2 LAST PATH I146
J 0
(-2175 400);
DISPLAY 1.021277 (-2175 400);
DISPLAY INVISIBLE (-2175 400);
FORCEPROP 2 LAST CDS_LIB standard
J 0
(-1925 350);
DISPLAY INVISIBLE (-1925 350);
FORCEADD OFFPAGE..1
R 2
(-75 1800);
FORCEPROP 2 LAST $XR0 215 
J 0
(111 1800);
DISPLAY 0.638298 (111 1800);
PAINT MONO (111 1800);
FORCEPROP 1 LAST OFFPAGE TRUE
J 2
(-400 1675);
DISPLAY 0.872340 (-400 1675);
DISPLAY INVISIBLE (-400 1675);
FORCEPROP 1 LAST COMMENT_BODY TRUE
J 2
(-200 1700);
DISPLAY 1.170213 (-200 1700);
PAINT GREEN (-200 1700);
DISPLAY INVISIBLE (-200 1700);
FORCEPROP 2 LAST PATH I148
J 0
(100 1875);
DISPLAY 1.021277 (100 1875);
DISPLAY INVISIBLE (100 1875);
FORCEPROP 2 LAST CDS_LIB standard
J 0
(-75 1800);
DISPLAY INVISIBLE (-75 1800);
FORCEADD OFFPAGE..2
(-75 3150);
FORCEPROP 2 LAST $XR1 219 
J 0
(234 3150);
DISPLAY 0.638298 (234 3150);
PAINT MONO (234 3150);
FORCEPROP 2 LAST $XR0 215 
J 0
(114 3150);
DISPLAY 0.638298 (114 3150);
PAINT MONO (114 3150);
FORCEPROP 2 LAST PATH I15
J 0
(250 3200);
DISPLAY 1.021277 (250 3200);
DISPLAY INVISIBLE (250 3200);
FORCEPROP 2 LAST CDS_LIB standard
J 0
(-75 3150);
DISPLAY INVISIBLE (-75 3150);
FORCEPROP 1 LAST COMMENT_BODY TRUE
J 0
(-120 3055);
DISPLAY 1.170213 (-120 3055);
PAINT GREEN (-120 3055);
DISPLAY INVISIBLE (-120 3055);
FORCEPROP 1 LAST OFFPAGE TRUE
J 0
(250 3025);
DISPLAY 1.170213 (250 3025);
PAINT GREEN (250 3025);
DISPLAY INVISIBLE (250 3025);
FORCEADD Q_RES..1
(-575 175);
FORCEPROP 1 LAST PART_NUMBER CS03322FB03
J 0
(-725 250);
DISPLAY 0.638298 (-725 250);
DISPLAY INVISIBLE (-725 250);
FORCEPROP 1 LAST VALUE 33.2
J 2
(-325 175);
DISPLAY 0.638298 (-325 175);
FORCEPROP 1 LAST TOLERANCE 1%
J 0
(-300 175);
DISPLAY 0.638298 (-300 175);
FORCEPROP 1 LAST MATERIAL CHIP
J 0
(-225 175);
DISPLAY 0.638298 (-225 175);
FORCEPROP 1 LAST $LOCATION R4558
J 0
(-775 175);
DISPLAY 0.638298 (-775 175);
FORCEPROP 1 LASTPIN (-675 175) $PN 1
J 0
(-663 187);
DISPLAY 0.787234 (-663 187);
PAINT MONO (-663 187);
FORCEPROP 1 LASTPIN (-475 175) $PN 2
J 0
(-513 187);
DISPLAY 0.787234 (-513 187);
PAINT MONO (-513 187);
FORCEPROP 1 LAST WATTAGE 1/16W
J 2
(-375 300);
DISPLAY 0.638298 (-375 300);
DISPLAY INVISIBLE (-375 300);
FORCEPROP 1 LAST PACK_TYPE 0402LF
J 0
(-725 300);
DISPLAY 0.638298 (-725 300);
DISPLAY INVISIBLE (-725 300);
FORCEPROP 1 LAST PATH I150
J 0
(-625 325);
DISPLAY 0.978723 (-625 325);
PAINT WHITE (-625 325);
DISPLAY INVISIBLE (-625 325);
FORCEPROP 2 LAST CDS_LIB pure_quanta
J 0
(-575 175);
DISPLAY INVISIBLE (-575 175);
FORCEPROP 0 LAST CDS_LOCATION R4558
J 0
(-225 225);
DISPLAY 1.021277 (-225 225);
DISPLAY INVISIBLE (-225 225);
FORCEPROP 0 LAST $SEC 1
J 0
(-225 225);
DISPLAY 0.680851 (-225 225);
PAINT MONO (-225 225);
DISPLAY INVISIBLE (-225 225);
FORCEPROP 0 LAST CDS_SEC 1
J 0
(-225 225);
DISPLAY 1.021277 (-225 225);
DISPLAY INVISIBLE (-225 225);
FORCEADD OFFPAGE..2
(-75 1750);
FORCEPROP 2 LAST $XR0 215 
J 0
(114 1750);
DISPLAY 0.638298 (114 1750);
PAINT MONO (114 1750);
FORCEPROP 1 LAST OFFPAGE TRUE
J 0
(250 1625);
DISPLAY 1.170213 (250 1625);
PAINT GREEN (250 1625);
DISPLAY INVISIBLE (250 1625);
FORCEPROP 1 LAST COMMENT_BODY TRUE
J 0
(-120 1655);
DISPLAY 1.170213 (-120 1655);
PAINT GREEN (-120 1655);
DISPLAY INVISIBLE (-120 1655);
FORCEPROP 2 LAST PATH I152
J 0
(100 1825);
DISPLAY 1.021277 (100 1825);
DISPLAY INVISIBLE (100 1825);
FORCEPROP 2 LAST CDS_LIB standard
J 0
(-75 1750);
DISPLAY INVISIBLE (-75 1750);
FORCEADD OFFPAGE..1
R 2
(950 175);
FORCEPROP 2 LAST $XR0 215 
J 0
(1136 175);
DISPLAY 0.638298 (1136 175);
PAINT MONO (1136 175);
FORCEPROP 2 LAST CDS_LIB standard
J 2
(950 175);
DISPLAY INVISIBLE (950 175);
FORCEPROP 2 LAST PATH I153
J 2
(900 250);
DISPLAY 1.021277 (900 250);
DISPLAY INVISIBLE (900 250);
FORCEPROP 1 LAST OFFPAGE TRUE
J 2
(625 50);
DISPLAY 0.872340 (625 50);
DISPLAY INVISIBLE (625 50);
FORCEPROP 1 LAST COMMENT_BODY TRUE
J 2
(825 75);
DISPLAY 1.170213 (825 75);
PAINT GREEN (825 75);
DISPLAY INVISIBLE (825 75);
FORCEADD OFFPAGE..2
R 2
(-1925 175);
FORCEPROP 2 LAST $XR0 145 
J 0
(-2210 175);
DISPLAY 0.638298 (-2210 175);
PAINT MONO (-2210 175);
FORCEPROP 1 LAST OFFPAGE TRUE
J 2
(-2250 50);
DISPLAY 0.872340 (-2250 50);
PAINT GREEN (-2250 50);
DISPLAY INVISIBLE (-2250 50);
FORCEPROP 1 LAST COMMENT_BODY TRUE
J 2
(-1880 80);
DISPLAY 0.872340 (-1880 80);
PAINT PEACH (-1880 80);
DISPLAY INVISIBLE (-1880 80);
FORCEPROP 2 LAST CDS_LIB standard
J 2
(-1925 175);
DISPLAY INVISIBLE (-1925 175);
FORCEPROP 2 LAST PATH I154
J 2
(-2100 250);
DISPLAY 1.021277 (-2100 250);
DISPLAY INVISIBLE (-2100 250);
FORCEADD OFFPAGE..2
(-75 1850);
FORCEPROP 2 LAST $XR0 215 
J 0
(114 1850);
DISPLAY 0.638298 (114 1850);
PAINT MONO (114 1850);
FORCEPROP 2 LAST PATH I156
J 0
(125 1900);
DISPLAY 1.021277 (125 1900);
DISPLAY INVISIBLE (125 1900);
FORCEPROP 2 LAST CDS_LIB standard
J 0
(-75 1850);
DISPLAY INVISIBLE (-75 1850);
FORCEPROP 1 LAST COMMENT_BODY TRUE
J 0
(-120 1755);
DISPLAY 1.170213 (-120 1755);
PAINT GREEN (-120 1755);
DISPLAY INVISIBLE (-120 1755);
FORCEPROP 1 LAST OFFPAGE TRUE
J 0
(250 1725);
DISPLAY 1.170213 (250 1725);
PAINT GREEN (250 1725);
DISPLAY INVISIBLE (250 1725);
FORCEADD OFFPAGE..1
R 2
(975 -125);
FORCEPROP 2 LAST $XR0 146 
J 0
(1161 -125);
DISPLAY 0.638298 (1161 -125);
PAINT MONO (1161 -125);
FORCEPROP 2 LAST CDS_LIB standard
J 0
(975 -125);
DISPLAY INVISIBLE (975 -125);
FORCEPROP 2 LAST PATH I157
J 0
(1150 -50);
DISPLAY 1.021277 (1150 -50);
DISPLAY INVISIBLE (1150 -50);
FORCEPROP 1 LAST COMMENT_BODY TRUE
J 2
(850 -225);
DISPLAY 1.170213 (850 -225);
PAINT GREEN (850 -225);
DISPLAY INVISIBLE (850 -225);
FORCEPROP 1 LAST OFFPAGE TRUE
J 2
(650 -250);
DISPLAY 0.872340 (650 -250);
DISPLAY INVISIBLE (650 -250);
FORCEADD Q_RES..1
(-600 -125);
FORCEPROP 1 LAST PART_NUMBER CS03322FB03
J 0
(-750 -50);
DISPLAY 0.638298 (-750 -50);
DISPLAY INVISIBLE (-750 -50);
FORCEPROP 1 LAST VALUE 33.2
J 2
(-350 -125);
DISPLAY 0.638298 (-350 -125);
FORCEPROP 1 LAST MATERIAL CHIP
J 0
(-250 -125);
DISPLAY 0.638298 (-250 -125);
FORCEPROP 1 LAST TOLERANCE 1%
J 0
(-325 -125);
DISPLAY 0.638298 (-325 -125);
FORCEPROP 1 LAST $LOCATION R4563
J 0
(-800 -125);
DISPLAY 0.638298 (-800 -125);
FORCEPROP 1 LASTPIN (-700 -125) $PN 1
J 0
(-688 -113);
DISPLAY 0.787234 (-688 -113);
PAINT MONO (-688 -113);
FORCEPROP 1 LASTPIN (-500 -125) $PN 2
J 0
(-538 -113);
DISPLAY 0.787234 (-538 -113);
PAINT MONO (-538 -113);
FORCEPROP 2 LAST CDS_LIB pure_quanta
J 0
(-600 -125);
DISPLAY INVISIBLE (-600 -125);
FORCEPROP 1 LAST PATH I158
J 0
(-650 25);
DISPLAY 0.978723 (-650 25);
PAINT WHITE (-650 25);
DISPLAY INVISIBLE (-650 25);
FORCEPROP 1 LAST WATTAGE 1/16W
J 2
(-400 0);
DISPLAY 0.638298 (-400 0);
DISPLAY INVISIBLE (-400 0);
FORCEPROP 1 LAST PACK_TYPE 0402LF
J 0
(-750 0);
DISPLAY 0.638298 (-750 0);
DISPLAY INVISIBLE (-750 0);
FORCEPROP 0 LAST CDS_LOCATION R4563
J 0
(-250 -75);
DISPLAY 1.021277 (-250 -75);
DISPLAY INVISIBLE (-250 -75);
FORCEPROP 0 LAST $SEC 1
J 0
(-250 -75);
DISPLAY 0.680851 (-250 -75);
PAINT MONO (-250 -75);
DISPLAY INVISIBLE (-250 -75);
FORCEPROP 0 LAST CDS_SEC 1
J 0
(-250 -75);
DISPLAY 1.021277 (-250 -75);
DISPLAY INVISIBLE (-250 -75);
FORCEADD OFFPAGE..2
R 2
(-1950 -125);
FORCEPROP 2 LAST $XR0 215 
J 0
(-2205 -125);
DISPLAY 0.638298 (-2205 -125);
PAINT MONO (-2205 -125);
FORCEPROP 2 LAST PATH I159
J 0
(-2200 -75);
DISPLAY 1.021277 (-2200 -75);
DISPLAY INVISIBLE (-2200 -75);
FORCEPROP 1 LAST OFFPAGE TRUE
J 2
(-2275 -250);
DISPLAY 0.872340 (-2275 -250);
PAINT GREEN (-2275 -250);
DISPLAY INVISIBLE (-2275 -250);
FORCEPROP 1 LAST COMMENT_BODY TRUE
J 2
(-1905 -220);
DISPLAY 0.872340 (-1905 -220);
PAINT PEACH (-1905 -220);
DISPLAY INVISIBLE (-1905 -220);
FORCEPROP 2 LAST CDS_LIB standard
J 2
(-1950 -125);
DISPLAY INVISIBLE (-1950 -125);
FORCEADD OFFPAGE..1
R 2
(-75 1700);
FORCEPROP 2 LAST $XR0 215 
J 0
(111 1700);
DISPLAY 0.638298 (111 1700);
PAINT MONO (111 1700);
FORCEPROP 1 LAST COMMENT_BODY TRUE
J 2
(-200 1600);
DISPLAY 1.170213 (-200 1600);
PAINT GREEN (-200 1600);
DISPLAY INVISIBLE (-200 1600);
FORCEPROP 1 LAST OFFPAGE TRUE
J 2
(-400 1575);
DISPLAY 0.872340 (-400 1575);
DISPLAY INVISIBLE (-400 1575);
FORCEPROP 2 LAST PATH I160
J 0
(100 1775);
DISPLAY 1.021277 (100 1775);
DISPLAY INVISIBLE (100 1775);
FORCEPROP 2 LAST CDS_LIB standard
J 0
(-75 1700);
DISPLAY INVISIBLE (-75 1700);
FORCEADD OFFPAGE..1
(-1950 -675);
FORCEPROP 2 LAST $XR1 307 
J 0
(-2322 -675);
DISPLAY 0.638298 (-2322 -675);
PAINT MONO (-2322 -675);
FORCEPROP 2 LAST $XR0 306 
J 0
(-2202 -675);
DISPLAY 0.638298 (-2202 -675);
PAINT MONO (-2202 -675);
FORCEPROP 2 LAST PATH I161
J 0
(-2200 -625);
DISPLAY 1.021277 (-2200 -625);
DISPLAY INVISIBLE (-2200 -625);
FORCEPROP 2 LAST CDS_LIB standard
J 0
(-1950 -675);
DISPLAY INVISIBLE (-1950 -675);
FORCEPROP 1 LAST COMMENT_BODY TRUE
J 0
(-1825 -775);
DISPLAY 1.170213 (-1825 -775);
PAINT GREEN (-1825 -775);
DISPLAY INVISIBLE (-1825 -775);
FORCEPROP 1 LAST OFFPAGE TRUE
J 0
(-1625 -800);
DISPLAY 0.872340 (-1625 -800);
DISPLAY INVISIBLE (-1625 -800);
FORCEADD OFFPAGE..2
(1000 -450);
FORCEPROP 2 LAST $XR0 215 
J 0
(1189 -450);
DISPLAY 0.638298 (1189 -450);
PAINT MONO (1189 -450);
FORCEPROP 2 LAST PATH I162
J 0
(1200 -400);
DISPLAY 1.021277 (1200 -400);
DISPLAY INVISIBLE (1200 -400);
FORCEPROP 1 LAST COMMENT_BODY TRUE
J 0
(955 -545);
DISPLAY 0.872340 (955 -545);
PAINT PEACH (955 -545);
DISPLAY INVISIBLE (955 -545);
FORCEPROP 1 LAST OFFPAGE TRUE
J 0
(1325 -575);
DISPLAY 0.872340 (1325 -575);
PAINT GREEN (1325 -575);
DISPLAY INVISIBLE (1325 -575);
FORCEPROP 2 LAST CDS_LIB standard
J 0
(1000 -450);
DISPLAY INVISIBLE (1000 -450);
FORCEADD OFFPAGE..2
(1000 -675);
FORCEPROP 2 LAST $XR0 215 
J 0
(1189 -675);
DISPLAY 0.638298 (1189 -675);
PAINT MONO (1189 -675);
FORCEPROP 2 LAST PATH I163
J 0
(1200 -625);
DISPLAY 1.021277 (1200 -625);
DISPLAY INVISIBLE (1200 -625);
FORCEPROP 2 LAST CDS_LIB standard
J 0
(1000 -675);
DISPLAY INVISIBLE (1000 -675);
FORCEPROP 1 LAST OFFPAGE TRUE
J 0
(1325 -800);
DISPLAY 0.872340 (1325 -800);
PAINT GREEN (1325 -800);
DISPLAY INVISIBLE (1325 -800);
FORCEPROP 1 LAST COMMENT_BODY TRUE
J 0
(955 -770);
DISPLAY 0.872340 (955 -770);
PAINT PEACH (955 -770);
DISPLAY INVISIBLE (955 -770);
FORCEADD Q_RES..1
(-575 -450);
FORCEPROP 1 LAST PART_NUMBER CS00002JB13
J 0
(-725 -400);
DISPLAY 0.510638 (-725 -400);
DISPLAY INVISIBLE (-725 -400);
FORCEPROP 1 LAST VALUE 0
J 2
(-425 -450);
DISPLAY 0.510638 (-425 -450);
FORCEPROP 1 LAST TOLERANCE 5%
J 0
(-400 -450);
DISPLAY 0.510638 (-400 -450);
FORCEPROP 1 LAST MATERIAL CHIP
J 0
(-325 -450);
DISPLAY 0.510638 (-325 -450);
FORCEPROP 1 LAST $LOCATION R3045
J 0
(-775 -450);
DISPLAY 0.510638 (-775 -450);
FORCEPROP 1 LASTPIN (-675 -450) $PN 1
J 0
(-663 -438);
DISPLAY 0.787234 (-663 -438);
FORCEPROP 1 LASTPIN (-475 -450) $PN 2
J 0
(-513 -438);
DISPLAY 0.787234 (-513 -438);
FORCEPROP 1 LAST WATTAGE 1/16W
J 2
(-425 -350);
DISPLAY 0.510638 (-425 -350);
DISPLAY INVISIBLE (-425 -350);
FORCEPROP 1 LAST PACK_TYPE 0402LF
J 0
(-725 -350);
DISPLAY 0.510638 (-725 -350);
DISPLAY INVISIBLE (-725 -350);
FORCEPROP 2 LAST CDS_LIB pure_quanta
J 0
(-575 -450);
PAINT MONO (-575 -450);
DISPLAY INVISIBLE (-575 -450);
FORCEPROP 1 LAST PATH I164
J 0
(-625 -300);
DISPLAY 0.978723 (-625 -300);
PAINT WHITE (-625 -300);
DISPLAY INVISIBLE (-625 -300);
FORCEPROP 2 LAST CDS_LOCATION R3045
J 0
(-625 -250);
DISPLAY 1.021277 (-625 -250);
DISPLAY INVISIBLE (-625 -250);
FORCEPROP 2 LAST $SEC 1
J 0
(-625 -250);
DISPLAY 0.680851 (-625 -250);
PAINT MONO (-625 -250);
DISPLAY INVISIBLE (-625 -250);
FORCEPROP 2 LAST CDS_SEC 1
J 0
(-625 -250);
DISPLAY 1.021277 (-625 -250);
DISPLAY INVISIBLE (-625 -250);
FORCEADD Q_RES..1
(-575 -675);
FORCEPROP 1 LAST PART_NUMBER CS00002JB13
J 0
(-725 -625);
DISPLAY 0.510638 (-725 -625);
DISPLAY INVISIBLE (-725 -625);
FORCEPROP 1 LAST TOLERANCE 5%
J 0
(-400 -675);
DISPLAY 0.510638 (-400 -675);
FORCEPROP 1 LAST MATERIAL CHIP
J 0
(-325 -675);
DISPLAY 0.510638 (-325 -675);
FORCEPROP 1 LAST VALUE 0
J 2
(-425 -675);
DISPLAY 0.510638 (-425 -675);
FORCEPROP 1 LAST $LOCATION R3046
J 0
(-775 -675);
DISPLAY 0.510638 (-775 -675);
FORCEPROP 1 LASTPIN (-675 -675) $PN 1
J 0
(-663 -663);
DISPLAY 0.787234 (-663 -663);
FORCEPROP 1 LASTPIN (-475 -675) $PN 2
J 0
(-513 -663);
DISPLAY 0.787234 (-513 -663);
FORCEPROP 2 LAST CDS_LIB pure_quanta
J 0
(-575 -675);
PAINT MONO (-575 -675);
DISPLAY INVISIBLE (-575 -675);
FORCEPROP 1 LAST PACK_TYPE 0402LF
J 0
(-725 -575);
DISPLAY 0.510638 (-725 -575);
DISPLAY INVISIBLE (-725 -575);
FORCEPROP 1 LAST WATTAGE 1/16W
J 2
(-425 -575);
DISPLAY 0.510638 (-425 -575);
DISPLAY INVISIBLE (-425 -575);
FORCEPROP 1 LAST PATH I165
J 0
(-625 -525);
DISPLAY 0.978723 (-625 -525);
PAINT WHITE (-625 -525);
DISPLAY INVISIBLE (-625 -525);
FORCEPROP 2 LAST CDS_LOCATION R3046
J 0
(-625 -475);
DISPLAY 1.021277 (-625 -475);
DISPLAY INVISIBLE (-625 -475);
FORCEPROP 2 LAST $SEC 1
J 0
(-625 -475);
DISPLAY 0.680851 (-625 -475);
PAINT MONO (-625 -475);
DISPLAY INVISIBLE (-625 -475);
FORCEPROP 2 LAST CDS_SEC 1
J 0
(-625 -475);
DISPLAY 1.021277 (-625 -475);
DISPLAY INVISIBLE (-625 -475);
FORCEADD OFFPAGE..1
(-1950 -450);
FORCEPROP 2 LAST $XR1 307 
J 0
(-2322 -450);
DISPLAY 0.638298 (-2322 -450);
PAINT MONO (-2322 -450);
FORCEPROP 2 LAST $XR0 306 
J 0
(-2202 -450);
DISPLAY 0.638298 (-2202 -450);
PAINT MONO (-2202 -450);
FORCEPROP 2 LAST PATH I166
J 0
(-2200 -400);
DISPLAY 1.021277 (-2200 -400);
DISPLAY INVISIBLE (-2200 -400);
FORCEPROP 1 LAST OFFPAGE TRUE
J 0
(-1625 -575);
DISPLAY 0.872340 (-1625 -575);
DISPLAY INVISIBLE (-1625 -575);
FORCEPROP 1 LAST COMMENT_BODY TRUE
J 0
(-1825 -550);
DISPLAY 1.170213 (-1825 -550);
PAINT GREEN (-1825 -550);
DISPLAY INVISIBLE (-1825 -550);
FORCEPROP 2 LAST CDS_LIB standard
J 0
(-1950 -450);
DISPLAY INVISIBLE (-1950 -450);
FORCEADD OFFPAGE..2
(1000 -1025);
FORCEPROP 2 LAST $XR1 183 
J 0
(1309 -1025);
DISPLAY 0.638298 (1309 -1025);
PAINT MONO (1309 -1025);
FORCEPROP 2 LAST $XR0 204 
J 0
(1189 -1025);
DISPLAY 0.638298 (1189 -1025);
PAINT MONO (1189 -1025);
FORCEPROP 2 LAST PATH I167
J 0
(1325 -975);
DISPLAY 1.021277 (1325 -975);
DISPLAY INVISIBLE (1325 -975);
FORCEPROP 2 LAST CDS_LIB standard
J 0
(1000 -1025);
PAINT MONO (1000 -1025);
DISPLAY INVISIBLE (1000 -1025);
FORCEPROP 1 LAST COMMENT_BODY TRUE
J 0
(955 -1120);
DISPLAY 1.170213 (955 -1120);
PAINT GREEN (955 -1120);
DISPLAY INVISIBLE (955 -1120);
FORCEPROP 1 LAST OFFPAGE TRUE
J 0
(1325 -1150);
DISPLAY 1.170213 (1325 -1150);
PAINT GREEN (1325 -1150);
DISPLAY INVISIBLE (1325 -1150);
FORCEADD OFFPAGE..2
(1000 -850);
FORCEPROP 2 LAST $XR1 183 
J 0
(1309 -850);
DISPLAY 0.638298 (1309 -850);
PAINT MONO (1309 -850);
FORCEPROP 2 LAST $XR0 198 
J 0
(1189 -850);
DISPLAY 0.638298 (1189 -850);
PAINT MONO (1189 -850);
FORCEPROP 2 LAST PATH I168
J 0
(1325 -800);
DISPLAY 1.021277 (1325 -800);
DISPLAY INVISIBLE (1325 -800);
FORCEPROP 1 LAST COMMENT_BODY TRUE
J 0
(955 -945);
DISPLAY 1.170213 (955 -945);
PAINT GREEN (955 -945);
DISPLAY INVISIBLE (955 -945);
FORCEPROP 1 LAST OFFPAGE TRUE
J 0
(1325 -975);
DISPLAY 1.170213 (1325 -975);
PAINT GREEN (1325 -975);
DISPLAY INVISIBLE (1325 -975);
FORCEPROP 2 LAST CDS_LIB standard
J 0
(1000 -850);
PAINT MONO (1000 -850);
DISPLAY INVISIBLE (1000 -850);
FORCEADD Q_RES..1
(-575 -850);
FORCEPROP 1 LAST PART_NUMBER CS00002JB13
J 0
(-625 -800);
DISPLAY 0.404255 (-625 -800);
DISPLAY INVISIBLE (-625 -800);
FORCEPROP 1 LAST WATTAGE 1/16W
J 2
(-400 -775);
DISPLAY 0.404255 (-400 -775);
FORCEPROP 1 LAST MATERIAL CHIP
J 0
(-625 -775);
DISPLAY 0.404255 (-625 -775);
FORCEPROP 1 LAST TOLERANCE 5%
J 0
(-400 -850);
DISPLAY 0.510638 (-400 -850);
FORCEPROP 1 LAST VALUE 0
J 2
(-425 -850);
DISPLAY 0.510638 (-425 -850);
FORCEPROP 1 LAST $LOCATION R700
J 0
(-800 -850);
DISPLAY 0.638298 (-800 -850);
FORCEPROP 1 LASTPIN (-675 -850) $PN 1
J 0
(-663 -838);
DISPLAY 0.787234 (-663 -838);
FORCEPROP 1 LASTPIN (-475 -850) $PN 2
J 0
(-513 -838);
DISPLAY 0.787234 (-513 -838);
FORCEPROP 1 LAST PACK_TYPE 0402LF
J 0
(-625 -750);
DISPLAY 0.404255 (-625 -750);
DISPLAY INVISIBLE (-625 -750);
FORCEPROP 2 LAST CDS_LIB pure_quanta
J 0
(-575 -850);
PAINT MONO (-575 -850);
DISPLAY INVISIBLE (-575 -850);
FORCEPROP 1 LAST PATH I169
J 0
(-625 -700);
DISPLAY 0.978723 (-625 -700);
PAINT WHITE (-625 -700);
DISPLAY INVISIBLE (-625 -700);
FORCEPROP 2 LAST CDS_LOCATION R700
J 0
(-625 -650);
DISPLAY 1.021277 (-625 -650);
DISPLAY INVISIBLE (-625 -650);
FORCEPROP 2 LAST $SEC 1
J 0
(-625 -650);
DISPLAY 0.680851 (-625 -650);
PAINT MONO (-625 -650);
DISPLAY INVISIBLE (-625 -650);
FORCEPROP 2 LAST CDS_SEC 1
J 0
(-625 -650);
DISPLAY 1.021277 (-625 -650);
DISPLAY INVISIBLE (-625 -650);
FORCEADD OFFPAGE..2
(-75 3050);
FORCEPROP 2 LAST $XR1 223 
J 0
(234 3050);
DISPLAY 0.638298 (234 3050);
PAINT MONO (234 3050);
FORCEPROP 2 LAST $XR0 219 
J 0
(114 3050);
DISPLAY 0.638298 (114 3050);
PAINT MONO (114 3050);
FORCEPROP 2 LAST PATH I17
J 0
(250 3100);
DISPLAY 1.021277 (250 3100);
DISPLAY INVISIBLE (250 3100);
FORCEPROP 2 LAST CDS_LIB standard
J 0
(-75 3050);
DISPLAY INVISIBLE (-75 3050);
FORCEPROP 1 LAST COMMENT_BODY TRUE
J 0
(-120 2955);
DISPLAY 1.170213 (-120 2955);
PAINT GREEN (-120 2955);
DISPLAY INVISIBLE (-120 2955);
FORCEPROP 1 LAST OFFPAGE TRUE
J 0
(250 2925);
DISPLAY 1.170213 (250 2925);
PAINT GREEN (250 2925);
DISPLAY INVISIBLE (250 2925);
FORCEADD Q_RES..1
(-575 -1025);
FORCEPROP 1 LAST PART_NUMBER CS00002JB13
J 0
(-625 -975);
DISPLAY 0.404255 (-625 -975);
DISPLAY INVISIBLE (-625 -975);
FORCEPROP 1 LAST PACK_TYPE 0402LF
J 0
(-625 -925);
DISPLAY 0.404255 (-625 -925);
FORCEPROP 1 LAST MATERIAL CHIP
J 0
(-625 -950);
DISPLAY 0.404255 (-625 -950);
FORCEPROP 1 LAST WATTAGE 1/16W
J 2
(-400 -950);
DISPLAY 0.404255 (-400 -950);
FORCEPROP 1 LAST TOLERANCE 5%
J 0
(-400 -1025);
DISPLAY 0.510638 (-400 -1025);
FORCEPROP 1 LAST VALUE 0
J 2
(-425 -1025);
DISPLAY 0.510638 (-425 -1025);
FORCEPROP 1 LAST $LOCATION R1944
J 0
(-800 -1025);
DISPLAY 0.510638 (-800 -1025);
FORCEPROP 1 LASTPIN (-675 -1025) $PN 1
J 0
(-663 -1013);
DISPLAY 0.787234 (-663 -1013);
PAINT MONO (-663 -1013);
FORCEPROP 1 LASTPIN (-475 -1025) $PN 2
J 0
(-513 -1013);
DISPLAY 0.787234 (-513 -1013);
PAINT MONO (-513 -1013);
FORCEPROP 2 LAST CDS_LIB pure_quanta
J 0
(-575 -1025);
DISPLAY INVISIBLE (-575 -1025);
FORCEPROP 1 LAST PATH I170
J 0
(-625 -875);
DISPLAY 0.978723 (-625 -875);
PAINT WHITE (-625 -875);
DISPLAY INVISIBLE (-625 -875);
FORCEPROP 0 LAST CDS_LOCATION R1944
J 0
(-625 -900);
DISPLAY 1.021277 (-625 -900);
DISPLAY INVISIBLE (-625 -900);
FORCEPROP 0 LAST $SEC 1
J 0
(-625 -900);
DISPLAY 0.680851 (-625 -900);
PAINT MONO (-625 -900);
DISPLAY INVISIBLE (-625 -900);
FORCEPROP 0 LAST CDS_SEC 1
J 0
(-625 -900);
DISPLAY 1.021277 (-625 -900);
DISPLAY INVISIBLE (-625 -900);
FORCEADD OFFPAGE..1
(-1950 -1025);
FORCEPROP 2 LAST $XR0 215 
J 0
(-2202 -1025);
DISPLAY 0.638298 (-2202 -1025);
PAINT MONO (-2202 -1025);
FORCEPROP 2 LAST PATH I171
J 0
(-2225 -975);
DISPLAY 1.021277 (-2225 -975);
DISPLAY INVISIBLE (-2225 -975);
FORCEPROP 2 LAST CDS_LIB standard
J 0
(-1950 -1025);
PAINT MONO (-1950 -1025);
DISPLAY INVISIBLE (-1950 -1025);
FORCEPROP 1 LAST OFFPAGE TRUE
J 0
(-1625 -1150);
DISPLAY 0.872340 (-1625 -1150);
DISPLAY INVISIBLE (-1625 -1150);
FORCEPROP 1 LAST COMMENT_BODY TRUE
J 0
(-1825 -1125);
DISPLAY 1.170213 (-1825 -1125);
PAINT GREEN (-1825 -1125);
DISPLAY INVISIBLE (-1825 -1125);
FORCEADD OFFPAGE..1
(-1950 -850);
FORCEPROP 2 LAST $XR0 215 
J 0
(-2202 -850);
DISPLAY 0.638298 (-2202 -850);
PAINT MONO (-2202 -850);
FORCEPROP 2 LAST PATH I172
J 0
(-2225 -800);
DISPLAY 1.021277 (-2225 -800);
DISPLAY INVISIBLE (-2225 -800);
FORCEPROP 2 LAST CDS_LIB standard
J 0
(-1950 -850);
PAINT MONO (-1950 -850);
DISPLAY INVISIBLE (-1950 -850);
FORCEPROP 1 LAST OFFPAGE TRUE
J 0
(-1625 -975);
DISPLAY 0.872340 (-1625 -975);
DISPLAY INVISIBLE (-1625 -975);
FORCEPROP 1 LAST COMMENT_BODY TRUE
J 0
(-1825 -950);
DISPLAY 1.170213 (-1825 -950);
PAINT GREEN (-1825 -950);
DISPLAY INVISIBLE (-1825 -950);
FORCEADD OFFPAGE..2
(1000 -1225);
FORCEPROP 2 LAST $XR0 215 
J 0
(1189 -1225);
DISPLAY 0.638298 (1189 -1225);
PAINT MONO (1189 -1225);
FORCEPROP 2 LAST PATH I173
J 0
(1200 -1175);
DISPLAY 1.021277 (1200 -1175);
DISPLAY INVISIBLE (1200 -1175);
FORCEPROP 2 LAST CDS_LIB standard
J 0
(1000 -1225);
PAINT MONO (1000 -1225);
DISPLAY INVISIBLE (1000 -1225);
FORCEPROP 1 LAST COMMENT_BODY TRUE
J 0
(955 -1320);
DISPLAY 1.170213 (955 -1320);
PAINT GREEN (955 -1320);
DISPLAY INVISIBLE (955 -1320);
FORCEPROP 1 LAST OFFPAGE TRUE
J 0
(1325 -1350);
DISPLAY 1.170213 (1325 -1350);
PAINT GREEN (1325 -1350);
DISPLAY INVISIBLE (1325 -1350);
FORCEADD OFFPAGE..2
(1000 -1400);
FORCEPROP 2 LAST $XR0 183 
J 0
(1189 -1400);
DISPLAY 0.638298 (1189 -1400);
PAINT MONO (1189 -1400);
FORCEPROP 2 LAST PATH I174
J 0
(1200 -1350);
DISPLAY 1.021277 (1200 -1350);
DISPLAY INVISIBLE (1200 -1350);
FORCEPROP 2 LAST CDS_LIB standard
J 0
(1000 -1400);
PAINT MONO (1000 -1400);
DISPLAY INVISIBLE (1000 -1400);
FORCEPROP 1 LAST OFFPAGE TRUE
J 0
(1325 -1525);
DISPLAY 0.872340 (1325 -1525);
PAINT GREEN (1325 -1525);
DISPLAY INVISIBLE (1325 -1525);
FORCEPROP 1 LAST COMMENT_BODY TRUE
J 0
(955 -1495);
DISPLAY 0.872340 (955 -1495);
PAINT PEACH (955 -1495);
DISPLAY INVISIBLE (955 -1495);
FORCEADD OFFPAGE..2
(1000 -1575);
FORCEPROP 2 LAST $XR1 245 
J 0
(1309 -1575);
DISPLAY 0.638298 (1309 -1575);
PAINT MONO (1309 -1575);
FORCEPROP 2 LAST $XR0 151 
J 0
(1189 -1575);
DISPLAY 0.638298 (1189 -1575);
PAINT MONO (1189 -1575);
FORCEPROP 1 LAST OFFPAGE TRUE
J 0
(1325 -1700);
DISPLAY 0.872340 (1325 -1700);
PAINT GREEN (1325 -1700);
DISPLAY INVISIBLE (1325 -1700);
FORCEPROP 1 LAST COMMENT_BODY TRUE
J 0
(955 -1670);
DISPLAY 0.872340 (955 -1670);
PAINT PEACH (955 -1670);
DISPLAY INVISIBLE (955 -1670);
FORCEPROP 2 LAST PATH I175
J 0
(1200 -1525);
DISPLAY 1.021277 (1200 -1525);
DISPLAY INVISIBLE (1200 -1525);
FORCEPROP 2 LAST CDS_LIB standard
J 0
(1000 -1575);
DISPLAY INVISIBLE (1000 -1575);
FORCEADD Q_RES..1
(-575 -1225);
FORCEPROP 1 LAST PART_NUMBER CS00002JB13
J 0
(-625 -1175);
DISPLAY 0.404255 (-625 -1175);
DISPLAY INVISIBLE (-625 -1175);
FORCEPROP 1 LAST MATERIAL CHIP
J 0
(-625 -1150);
DISPLAY 0.404255 (-625 -1150);
FORCEPROP 1 LAST PACK_TYPE 0402LF
J 0
(-625 -1125);
DISPLAY 0.404255 (-625 -1125);
FORCEPROP 1 LAST WATTAGE 1/16W
J 2
(-400 -1150);
DISPLAY 0.404255 (-400 -1150);
FORCEPROP 1 LAST TOLERANCE 5%
J 0
(-400 -1225);
DISPLAY 0.510638 (-400 -1225);
FORCEPROP 1 LAST VALUE 0
J 2
(-425 -1225);
DISPLAY 0.510638 (-425 -1225);
FORCEPROP 1 LAST $LOCATION R3049
J 0
(-800 -1225);
DISPLAY 0.510638 (-800 -1225);
FORCEPROP 1 LASTPIN (-675 -1225) $PN 1
J 0
(-663 -1213);
DISPLAY 0.787234 (-663 -1213);
PAINT MONO (-663 -1213);
FORCEPROP 1 LASTPIN (-475 -1225) $PN 2
J 0
(-513 -1213);
DISPLAY 0.787234 (-513 -1213);
PAINT MONO (-513 -1213);
FORCEPROP 2 LAST CDS_LIB pure_quanta
J 0
(-575 -1225);
DISPLAY INVISIBLE (-575 -1225);
FORCEPROP 1 LAST PATH I176
J 0
(-625 -1075);
DISPLAY 0.978723 (-625 -1075);
PAINT WHITE (-625 -1075);
DISPLAY INVISIBLE (-625 -1075);
FORCEPROP 0 LAST CDS_LOCATION R3049
J 0
(-625 -1100);
DISPLAY 1.021277 (-625 -1100);
DISPLAY INVISIBLE (-625 -1100);
FORCEPROP 0 LAST $SEC 1
J 0
(-625 -1100);
DISPLAY 0.680851 (-625 -1100);
PAINT MONO (-625 -1100);
DISPLAY INVISIBLE (-625 -1100);
FORCEPROP 0 LAST CDS_SEC 1
J 0
(-625 -1100);
DISPLAY 1.021277 (-625 -1100);
DISPLAY INVISIBLE (-625 -1100);
FORCEADD Q_RES..1
(-575 -1400);
FORCEPROP 1 LAST PART_NUMBER CS00002JB13
J 0
(-625 -1350);
DISPLAY 0.404255 (-625 -1350);
DISPLAY INVISIBLE (-625 -1350);
FORCEPROP 1 LAST MATERIAL CHIP
J 0
(-325 -1400);
DISPLAY 0.510638 (-325 -1400);
FORCEPROP 1 LAST VALUE 0
J 2
(-425 -1400);
DISPLAY 0.510638 (-425 -1400);
FORCEPROP 1 LAST TOLERANCE 5%
J 0
(-400 -1400);
DISPLAY 0.510638 (-400 -1400);
FORCEPROP 1 LAST $LOCATION R2155
J 0
(-775 -1400);
DISPLAY 0.510638 (-775 -1400);
FORCEPROP 1 LASTPIN (-675 -1400) $PN 1
J 0
(-663 -1388);
DISPLAY 0.787234 (-663 -1388);
PAINT MONO (-663 -1388);
FORCEPROP 1 LASTPIN (-475 -1400) $PN 2
J 0
(-513 -1388);
DISPLAY 0.787234 (-513 -1388);
PAINT MONO (-513 -1388);
FORCEPROP 1 LAST PATH I177
J 0
(-625 -1250);
DISPLAY 0.978723 (-625 -1250);
PAINT WHITE (-625 -1250);
DISPLAY INVISIBLE (-625 -1250);
FORCEPROP 2 LAST CDS_LIB pure_quanta
J 0
(-575 -1400);
DISPLAY INVISIBLE (-575 -1400);
FORCEPROP 1 LAST PACK_TYPE 0402LF
J 0
(-325 -1400);
DISPLAY 0.510638 (-325 -1400);
DISPLAY INVISIBLE (-325 -1400);
FORCEPROP 1 LAST WATTAGE 1/16W
J 2
(-400 -1325);
DISPLAY 0.404255 (-400 -1325);
DISPLAY INVISIBLE (-400 -1325);
FORCEPROP 0 LAST CDS_LOCATION R2155
J 0
(-775 -1350);
DISPLAY 1.021277 (-775 -1350);
DISPLAY INVISIBLE (-775 -1350);
FORCEPROP 0 LAST $SEC 1
J 0
(-775 -1350);
DISPLAY 0.680851 (-775 -1350);
PAINT MONO (-775 -1350);
DISPLAY INVISIBLE (-775 -1350);
FORCEPROP 0 LAST CDS_SEC 1
J 0
(-775 -1350);
DISPLAY 1.021277 (-775 -1350);
DISPLAY INVISIBLE (-775 -1350);
FORCEADD Q_RES..1
(-575 -1575);
FORCEPROP 1 LAST PART_NUMBER CS00002JB13
J 0
(-625 -1525);
DISPLAY 0.404255 (-625 -1525);
DISPLAY INVISIBLE (-625 -1525);
FORCEPROP 1 LAST VALUE 0
J 2
(-425 -1575);
DISPLAY 0.510638 (-425 -1575);
FORCEPROP 1 LAST MATERIAL CHIP
J 0
(-325 -1575);
DISPLAY 0.510638 (-325 -1575);
FORCEPROP 1 LAST TOLERANCE 5%
J 0
(-400 -1575);
DISPLAY 0.510638 (-400 -1575);
FORCEPROP 1 LAST $LOCATION R2792
J 0
(-775 -1575);
DISPLAY 0.510638 (-775 -1575);
FORCEPROP 1 LASTPIN (-675 -1575) $PN 1
J 0
(-663 -1563);
DISPLAY 0.787234 (-663 -1563);
PAINT MONO (-663 -1563);
FORCEPROP 1 LASTPIN (-475 -1575) $PN 2
J 0
(-513 -1563);
DISPLAY 0.787234 (-513 -1563);
PAINT MONO (-513 -1563);
FORCEPROP 1 LAST PATH I178
J 0
(-625 -1425);
DISPLAY 0.978723 (-625 -1425);
PAINT WHITE (-625 -1425);
DISPLAY INVISIBLE (-625 -1425);
FORCEPROP 1 LAST WATTAGE 1/16W
J 2
(-400 -1500);
DISPLAY 0.404255 (-400 -1500);
DISPLAY INVISIBLE (-400 -1500);
FORCEPROP 1 LAST PACK_TYPE 0402LF
J 0
(-325 -1575);
DISPLAY 0.510638 (-325 -1575);
DISPLAY INVISIBLE (-325 -1575);
FORCEPROP 2 LAST CDS_LIB pure_quanta
J 0
(-575 -1575);
DISPLAY INVISIBLE (-575 -1575);
FORCEPROP 0 LAST CDS_LOCATION R2792
J 0
(-775 -1525);
DISPLAY 1.021277 (-775 -1525);
DISPLAY INVISIBLE (-775 -1525);
FORCEPROP 0 LAST $SEC 1
J 0
(-775 -1525);
DISPLAY 0.680851 (-775 -1525);
PAINT MONO (-775 -1525);
DISPLAY INVISIBLE (-775 -1525);
FORCEPROP 0 LAST CDS_SEC 1
J 0
(-775 -1525);
DISPLAY 1.021277 (-775 -1525);
DISPLAY INVISIBLE (-775 -1525);
FORCEADD OFFPAGE..1
(-1950 -1225);
FORCEPROP 2 LAST $XR3 183 
J 0
(-2562 -1225);
DISPLAY 0.638298 (-2562 -1225);
PAINT MONO (-2562 -1225);
FORCEPROP 2 LAST $XR2 305 
J 0
(-2442 -1225);
DISPLAY 0.638298 (-2442 -1225);
PAINT MONO (-2442 -1225);
FORCEPROP 2 LAST $XR1 301 
J 0
(-2322 -1225);
DISPLAY 0.638298 (-2322 -1225);
PAINT MONO (-2322 -1225);
FORCEPROP 2 LAST $XR0 228 
J 0
(-2202 -1225);
DISPLAY 0.638298 (-2202 -1225);
PAINT MONO (-2202 -1225);
FORCEPROP 2 LAST PATH I179
J 0
(-2225 -1175);
DISPLAY 1.021277 (-2225 -1175);
DISPLAY INVISIBLE (-2225 -1175);
FORCEPROP 2 LAST CDS_LIB standard
J 0
(-1950 -1225);
PAINT MONO (-1950 -1225);
DISPLAY INVISIBLE (-1950 -1225);
FORCEPROP 1 LAST OFFPAGE TRUE
J 0
(-1625 -1350);
DISPLAY 0.872340 (-1625 -1350);
DISPLAY INVISIBLE (-1625 -1350);
FORCEPROP 1 LAST COMMENT_BODY TRUE
J 0
(-1825 -1325);
DISPLAY 1.170213 (-1825 -1325);
PAINT GREEN (-1825 -1325);
DISPLAY INVISIBLE (-1825 -1325);
FORCEADD OFFPAGE..2
(-75 2950);
FORCEPROP 2 LAST $XR0 154 
J 0
(114 2950);
DISPLAY 0.638298 (114 2950);
PAINT MONO (114 2950);
FORCEPROP 2 LAST PATH I18
J 0
(125 3000);
DISPLAY 1.021277 (125 3000);
DISPLAY INVISIBLE (125 3000);
FORCEPROP 2 LAST CDS_LIB standard
J 0
(-75 2950);
DISPLAY INVISIBLE (-75 2950);
FORCEPROP 1 LAST COMMENT_BODY TRUE
J 0
(-120 2855);
DISPLAY 1.170213 (-120 2855);
PAINT GREEN (-120 2855);
DISPLAY INVISIBLE (-120 2855);
FORCEPROP 1 LAST OFFPAGE TRUE
J 0
(250 2825);
DISPLAY 1.170213 (250 2825);
PAINT GREEN (250 2825);
DISPLAY INVISIBLE (250 2825);
FORCEADD OFFPAGE..1
(-1950 -1400);
FORCEPROP 2 LAST $XR0 215 
J 0
(-2202 -1400);
DISPLAY 0.638298 (-2202 -1400);
PAINT MONO (-2202 -1400);
FORCEPROP 1 LAST OFFPAGE TRUE
J 0
(-1625 -1525);
DISPLAY 0.872340 (-1625 -1525);
DISPLAY INVISIBLE (-1625 -1525);
FORCEPROP 1 LAST COMMENT_BODY TRUE
J 0
(-1825 -1500);
DISPLAY 1.170213 (-1825 -1500);
PAINT GREEN (-1825 -1500);
DISPLAY INVISIBLE (-1825 -1500);
FORCEPROP 2 LAST PATH I180
J 0
(-2225 -1350);
DISPLAY 1.021277 (-2225 -1350);
DISPLAY INVISIBLE (-2225 -1350);
FORCEPROP 2 LAST CDS_LIB standard
J 0
(-1950 -1400);
DISPLAY INVISIBLE (-1950 -1400);
FORCEADD OFFPAGE..2
(-3175 -1525);
FORCEPROP 2 LAST $XR1 184 
J 0
(-2866 -1525);
DISPLAY 0.638298 (-2866 -1525);
PAINT MONO (-2866 -1525);
FORCEPROP 2 LAST $XR0 204 
J 0
(-2986 -1525);
DISPLAY 0.638298 (-2986 -1525);
PAINT MONO (-2986 -1525);
FORCEPROP 1 LAST COMMENT_BODY TRUE
J 0
(-3220 -1620);
DISPLAY 0.872340 (-3220 -1620);
PAINT PEACH (-3220 -1620);
DISPLAY INVISIBLE (-3220 -1620);
FORCEPROP 1 LAST OFFPAGE TRUE
J 0
(-2850 -1650);
DISPLAY 0.872340 (-2850 -1650);
PAINT GREEN (-2850 -1650);
DISPLAY INVISIBLE (-2850 -1650);
FORCEPROP 2 LAST PATH I181
J 0
(-2850 -1475);
DISPLAY 1.021277 (-2850 -1475);
DISPLAY INVISIBLE (-2850 -1475);
FORCEPROP 2 LAST CDS_LIB standard
J 0
(-3175 -1525);
PAINT MONO (-3175 -1525);
DISPLAY INVISIBLE (-3175 -1525);
FORCEADD OFFPAGE..2
(-3175 -1325);
FORCEPROP 2 LAST $XR0 215 
J 0
(-2986 -1325);
DISPLAY 0.638298 (-2986 -1325);
PAINT MONO (-2986 -1325);
FORCEPROP 1 LAST COMMENT_BODY TRUE
J 0
(-3220 -1420);
DISPLAY 0.872340 (-3220 -1420);
PAINT PEACH (-3220 -1420);
DISPLAY INVISIBLE (-3220 -1420);
FORCEPROP 1 LAST OFFPAGE TRUE
J 0
(-2850 -1450);
DISPLAY 0.872340 (-2850 -1450);
PAINT GREEN (-2850 -1450);
DISPLAY INVISIBLE (-2850 -1450);
FORCEPROP 2 LAST CDS_LIB standard
J 0
(-3175 -1325);
PAINT MONO (-3175 -1325);
DISPLAY INVISIBLE (-3175 -1325);
FORCEPROP 2 LAST PATH I182
J 0
(-2975 -1275);
DISPLAY 1.021277 (-2975 -1275);
DISPLAY INVISIBLE (-2975 -1275);
FORCEADD Q_RES..1
(-4550 -1325);
FORCEPROP 1 LAST PART_NUMBER CS00002JB13
J 0
(-4600 -1275);
DISPLAY 0.404255 (-4600 -1275);
DISPLAY INVISIBLE (-4600 -1275);
FORCEPROP 1 LAST MATERIAL CHIP
J 0
(-4300 -1325);
DISPLAY 0.510638 (-4300 -1325);
FORCEPROP 1 LAST VALUE 0
J 2
(-4400 -1325);
DISPLAY 0.510638 (-4400 -1325);
FORCEPROP 1 LAST TOLERANCE 5%
J 0
(-4375 -1325);
DISPLAY 0.510638 (-4375 -1325);
FORCEPROP 1 LAST $LOCATION R2347
J 0
(-4750 -1325);
DISPLAY 0.510638 (-4750 -1325);
FORCEPROP 1 LASTPIN (-4650 -1325) $PN 1
J 0
(-4638 -1313);
DISPLAY 0.787234 (-4638 -1313);
PAINT MONO (-4638 -1313);
FORCEPROP 1 LASTPIN (-4450 -1325) $PN 2
J 0
(-4488 -1313);
DISPLAY 0.787234 (-4488 -1313);
PAINT MONO (-4488 -1313);
FORCEPROP 1 LAST PACK_TYPE 0402LF
J 0
(-4300 -1325);
DISPLAY 0.510638 (-4300 -1325);
DISPLAY INVISIBLE (-4300 -1325);
FORCEPROP 1 LAST WATTAGE 1/16W
J 2
(-4375 -1250);
DISPLAY 0.404255 (-4375 -1250);
DISPLAY INVISIBLE (-4375 -1250);
FORCEPROP 1 LAST PATH I183
J 0
(-4600 -1175);
DISPLAY 0.978723 (-4600 -1175);
PAINT WHITE (-4600 -1175);
DISPLAY INVISIBLE (-4600 -1175);
FORCEPROP 2 LAST CDS_LIB pure_quanta
J 0
(-4550 -1325);
DISPLAY INVISIBLE (-4550 -1325);
FORCEPROP 0 LAST CDS_LOCATION R2347
J 0
(-4750 -1275);
DISPLAY 1.021277 (-4750 -1275);
DISPLAY INVISIBLE (-4750 -1275);
FORCEPROP 0 LAST $SEC 1
J 0
(-4750 -1275);
DISPLAY 0.680851 (-4750 -1275);
PAINT MONO (-4750 -1275);
DISPLAY INVISIBLE (-4750 -1275);
FORCEPROP 0 LAST CDS_SEC 1
J 0
(-4750 -1275);
DISPLAY 1.021277 (-4750 -1275);
DISPLAY INVISIBLE (-4750 -1275);
FORCEADD Q_RES..1
(-4550 -1525);
FORCEPROP 1 LAST PART_NUMBER CS00002JB13
J 0
(-4600 -1475);
DISPLAY 0.404255 (-4600 -1475);
DISPLAY INVISIBLE (-4600 -1475);
FORCEPROP 1 LAST VALUE 0
J 2
(-4400 -1525);
DISPLAY 0.510638 (-4400 -1525);
FORCEPROP 1 LAST TOLERANCE 5%
J 0
(-4375 -1525);
DISPLAY 0.510638 (-4375 -1525);
FORCEPROP 1 LAST MATERIAL CHIP
J 0
(-4300 -1525);
DISPLAY 0.510638 (-4300 -1525);
FORCEPROP 1 LAST $LOCATION R2348
J 0
(-4750 -1525);
DISPLAY 0.510638 (-4750 -1525);
FORCEPROP 1 LASTPIN (-4650 -1525) $PN 1
J 0
(-4638 -1513);
DISPLAY 0.787234 (-4638 -1513);
PAINT MONO (-4638 -1513);
FORCEPROP 1 LASTPIN (-4450 -1525) $PN 2
J 0
(-4488 -1513);
DISPLAY 0.787234 (-4488 -1513);
PAINT MONO (-4488 -1513);
FORCEPROP 2 LAST CDS_LIB pure_quanta
J 0
(-4550 -1525);
DISPLAY INVISIBLE (-4550 -1525);
FORCEPROP 1 LAST WATTAGE 1/16W
J 2
(-4375 -1450);
DISPLAY 0.404255 (-4375 -1450);
DISPLAY INVISIBLE (-4375 -1450);
FORCEPROP 1 LAST PACK_TYPE 0402LF
J 0
(-4300 -1525);
DISPLAY 0.510638 (-4300 -1525);
DISPLAY INVISIBLE (-4300 -1525);
FORCEPROP 1 LAST PATH I184
J 0
(-4600 -1375);
DISPLAY 0.978723 (-4600 -1375);
PAINT WHITE (-4600 -1375);
DISPLAY INVISIBLE (-4600 -1375);
FORCEPROP 0 LAST CDS_LOCATION R2348
J 0
(-4750 -1475);
DISPLAY 1.021277 (-4750 -1475);
DISPLAY INVISIBLE (-4750 -1475);
FORCEPROP 0 LAST $SEC 1
J 0
(-4750 -1475);
DISPLAY 0.680851 (-4750 -1475);
PAINT MONO (-4750 -1475);
DISPLAY INVISIBLE (-4750 -1475);
FORCEPROP 0 LAST CDS_SEC 1
J 0
(-4750 -1475);
DISPLAY 1.021277 (-4750 -1475);
DISPLAY INVISIBLE (-4750 -1475);
FORCEADD OFFPAGE..1
(-5775 -1325);
FORCEPROP 2 LAST $XR0 134 
J 0
(-6027 -1325);
DISPLAY 0.638298 (-6027 -1325);
PAINT MONO (-6027 -1325);
FORCEPROP 2 LAST PATH I185
J 0
(-6050 -1275);
DISPLAY 1.021277 (-6050 -1275);
DISPLAY INVISIBLE (-6050 -1275);
FORCEPROP 1 LAST OFFPAGE TRUE
J 0
(-5450 -1450);
DISPLAY 0.872340 (-5450 -1450);
DISPLAY INVISIBLE (-5450 -1450);
FORCEPROP 1 LAST COMMENT_BODY TRUE
J 0
(-5650 -1425);
DISPLAY 1.170213 (-5650 -1425);
PAINT GREEN (-5650 -1425);
DISPLAY INVISIBLE (-5650 -1425);
FORCEPROP 2 LAST CDS_LIB standard
J 0
(-5775 -1325);
DISPLAY INVISIBLE (-5775 -1325);
FORCEADD OFFPAGE..1
(-5775 -1525);
FORCEPROP 2 LAST $XR0 215 
J 0
(-6027 -1525);
DISPLAY 0.638298 (-6027 -1525);
PAINT MONO (-6027 -1525);
FORCEPROP 1 LAST OFFPAGE TRUE
J 0
(-5450 -1650);
DISPLAY 0.872340 (-5450 -1650);
DISPLAY INVISIBLE (-5450 -1650);
FORCEPROP 1 LAST COMMENT_BODY TRUE
J 0
(-5650 -1625);
DISPLAY 1.170213 (-5650 -1625);
PAINT GREEN (-5650 -1625);
DISPLAY INVISIBLE (-5650 -1625);
FORCEPROP 2 LAST PATH I186
J 0
(-6050 -1475);
DISPLAY 1.021277 (-6050 -1475);
DISPLAY INVISIBLE (-6050 -1475);
FORCEPROP 2 LAST CDS_LIB standard
J 0
(-5775 -1525);
DISPLAY INVISIBLE (-5775 -1525);
FORCEADD CONN3_210HP1030BR1..1
(-5050 3575);
PAINT AQUA (-5050 3575);
FORCEPROP 1 LAST PART_NUMBER DFHD03MS213
J 0
(-5100 3750);
DISPLAY 0.723404 (-5100 3750);
PAINT WHITE (-5100 3750);
DISPLAY INVISIBLE (-5100 3750);
FORCEPROP 2 LAST VALUE CONN3_210-HP1-030BR1
J 0
(-5100 3850);
DISPLAY 0.723404 (-5100 3850);
PAINT AQUA (-5100 3850);
FORCEPROP 2 LAST PART_TYPE THLF
J 0
(-5100 3900);
DISPLAY 1.021277 (-5100 3900);
FORCEPROP 1 LAST MATERIAL IO
J 0
(-5113 3699);
DISPLAY 0.723404 (-5113 3699);
PAINT SKYBLUE (-5113 3699);
FORCEPROP 1 LAST $LOCATION JP15
J 0
(-5100 3800);
DISPLAY 0.723404 (-5100 3800);
PAINT AQUA (-5100 3800);
FORCEPROP 0 LASTPIN (-5250 3625) $PN 1
J 2
(-5260 3635);
DISPLAY 0.680851 (-5260 3635);
PAINT MONO (-5260 3635);
FORCEPROP 0 LASTPIN (-5250 3575) $PN 2
J 2
(-5260 3585);
DISPLAY 0.680851 (-5260 3585);
PAINT MONO (-5260 3585);
FORCEPROP 0 LASTPIN (-5250 3525) $PN 3
J 2
(-5260 3535);
DISPLAY 0.680851 (-5260 3535);
PAINT MONO (-5260 3535);
FORCEPROP 1 LAST PATH I187
J 0
(-5050 3575);
DISPLAY 0.723404 (-5050 3575);
PAINT GREEN (-5050 3575);
DISPLAY INVISIBLE (-5050 3575);
FORCEPROP 2 LAST CDS_LIB pure_quanta
J 0
(-5050 3575);
DISPLAY INVISIBLE (-5050 3575);
FORCEPROP 1 LAST CDS_LMAN_SYM_OUTLINE -50,100,50,-100
J 0
(-5050 3575);
DISPLAY 0.468085 (-5050 3575);
PAINT GREEN (-5050 3575);
DISPLAY INVISIBLE (-5050 3575);
FORCEPROP 1 LAST NEEDS_NO_SIZE TRUE
J 0
(-5050 3575);
DISPLAY 0.723404 (-5050 3575);
PAINT GREEN (-5050 3575);
DISPLAY INVISIBLE (-5050 3575);
FORCEPROP 0 LAST CDS_LOCATION JP15
J 0
(-5100 3950);
DISPLAY 1.021277 (-5100 3950);
DISPLAY INVISIBLE (-5100 3950);
FORCEPROP 0 LAST $SEC 1
J 0
(-5100 3950);
DISPLAY 0.680851 (-5100 3950);
PAINT MONO (-5100 3950);
DISPLAY INVISIBLE (-5100 3950);
FORCEPROP 0 LAST CDS_SEC 1
J 0
(-5100 3950);
DISPLAY 1.021277 (-5100 3950);
DISPLAY INVISIBLE (-5100 3950);
FORCEADD UNIVERSAL_POWER..1
(-6000 4075);
FORCEPROP 3 LASTPIN (-6000 4025) SIG_NAME P3V3_AUX\g
J 0
(-5990 4035);
DISPLAY 0.659574 (-5990 4035);
PAINT MONO (-5990 4035);
DISPLAY INVISIBLE (-5990 4035);
FORCEPROP 1 LAST HDL_POWER P3V3_AUX
J 1
(-6000 4125);
DISPLAY 0.872340 (-6000 4125);
PAINT GREEN (-6000 4125);
FORCEPROP 1 LAST PATH I188
J 0
(-5950 4100);
DISPLAY 0.872340 (-5950 4100);
PAINT AQUA (-5950 4100);
DISPLAY INVISIBLE (-5950 4100);
FORCEPROP 2 LAST CDS_LIB logical_power
J 0
(-6000 4075);
DISPLAY INVISIBLE (-6000 4075);
FORCEADD UNIVERSAL_GND..1
(-6000 3100);
FORCEPROP 3 LASTPIN (-6000 3150) SIG_NAME GND\g
J 0
(-5990 3160);
DISPLAY 0.659574 (-5990 3160);
PAINT MONO (-5990 3160);
DISPLAY INVISIBLE (-5990 3160);
FORCEPROP 1 LAST PATH I189
J 0
(-5925 3100);
DISPLAY 0.872340 (-5925 3100);
PAINT AQUA (-5925 3100);
DISPLAY INVISIBLE (-5925 3100);
FORCEPROP 2 LAST CDS_LIB logical_power
J 0
(-6000 3100);
DISPLAY INVISIBLE (-6000 3100);
FORCEPROP 1 LAST HDL_POWER GND
J 1
(-5975 3025);
DISPLAY 0.872340 (-5975 3025);
PAINT GREEN (-5975 3025);
DISPLAY INVISIBLE (-5975 3025);
FORCEADD OFFPAGE..2
(-75 3000);
FORCEPROP 2 LAST $XR2 220 
J 0
(354 3000);
DISPLAY 0.638298 (354 3000);
PAINT MONO (354 3000);
FORCEPROP 2 LAST $XR1 161 
J 0
(234 3000);
DISPLAY 0.638298 (234 3000);
PAINT MONO (234 3000);
FORCEPROP 2 LAST $XR0 155 
J 0
(114 3000);
DISPLAY 0.638298 (114 3000);
PAINT MONO (114 3000);
FORCEPROP 2 LAST PATH I19
J 0
(375 3050);
DISPLAY 1.021277 (375 3050);
DISPLAY INVISIBLE (375 3050);
FORCEPROP 2 LAST CDS_LIB standard
J 0
(-75 3000);
DISPLAY INVISIBLE (-75 3000);
FORCEPROP 1 LAST COMMENT_BODY TRUE
J 0
(-120 2905);
DISPLAY 1.170213 (-120 2905);
PAINT GREEN (-120 2905);
DISPLAY INVISIBLE (-120 2905);
FORCEPROP 1 LAST OFFPAGE TRUE
J 0
(250 2875);
DISPLAY 1.170213 (250 2875);
PAINT GREEN (250 2875);
DISPLAY INVISIBLE (250 2875);
FORCEADD Q_RES..2
(-6000 3325);
FORCEPROP 1 LAST PART_NUMBER CS31002FB08
J 0
(-5960 3200);
DISPLAY 0.978723 (-5960 3200);
DISPLAY INVISIBLE (-5960 3200);
FORCEPROP 1 LAST MATERIAL CHIP
J 0
(-5960 3250);
DISPLAY 0.978723 (-5960 3250);
FORCEPROP 1 LAST WATTAGE 1/16W
J 0
(-5960 3300);
DISPLAY 0.978723 (-5960 3300);
FORCEPROP 1 LAST VALUE 10K
J 0
(-5955 3400);
DISPLAY 0.978723 (-5955 3400);
FORCEPROP 1 LAST TOLERANCE 1%
J 0
(-5955 3350);
DISPLAY 0.978723 (-5955 3350);
FORCEPROP 1 LAST PACK_TYPE 0402LF
J 0
(-5960 3150);
DISPLAY 0.978723 (-5960 3150);
FORCEPROP 1 LAST $LOCATION R1495
J 0
(-5955 3450);
DISPLAY 0.978723 (-5955 3450);
FORCEPROP 1 LASTPIN (-6000 3425) $PN 1
J 0
(-5995 3387);
DISPLAY 0.787234 (-5995 3387);
PAINT MONO (-5995 3387);
FORCEPROP 1 LASTPIN (-6000 3225) $PN 2
J 0
(-5995 3235);
DISPLAY 0.787234 (-5995 3235);
PAINT MONO (-5995 3235);
FORCEPROP 1 LAST PATH I190
J 0
(-5950 3500);
DISPLAY 0.978723 (-5950 3500);
PAINT WHITE (-5950 3500);
DISPLAY INVISIBLE (-5950 3500);
FORCEPROP 2 LAST CDS_LIB pure_quanta
J 0
(-6000 3325);
PAINT MONO (-6000 3325);
DISPLAY INVISIBLE (-6000 3325);
FORCEPROP 2 LAST CDS_LOCATION R1495
J 0
(-6050 3525);
DISPLAY 1.021277 (-6050 3525);
DISPLAY INVISIBLE (-6050 3525);
FORCEPROP 0 LAST $SEC 1
J 0
(-5950 3500);
DISPLAY 0.680851 (-5950 3500);
PAINT MONO (-5950 3500);
DISPLAY INVISIBLE (-5950 3500);
FORCEPROP 2 LAST CDS_SEC 1
J 0
(-6050 3525);
DISPLAY 1.021277 (-6050 3525);
DISPLAY INVISIBLE (-6050 3525);
FORCEADD Q_RES..2
(-6000 3875);
FORCEPROP 1 LAST PART_NUMBER CS21002FB06
J 0
(-5960 3750);
DISPLAY 0.978723 (-5960 3750);
DISPLAY INVISIBLE (-5960 3750);
FORCEPROP 1 LAST TOLERANCE 1%
J 0
(-5955 3900);
DISPLAY 0.978723 (-5955 3900);
FORCEPROP 1 LAST PACK_TYPE 0402LF
J 0
(-5960 3700);
DISPLAY 0.978723 (-5960 3700);
FORCEPROP 1 LAST VALUE 1K
J 0
(-5955 3950);
DISPLAY 0.978723 (-5955 3950);
FORCEPROP 1 LAST WATTAGE 1/16W
J 0
(-5960 3850);
DISPLAY 0.978723 (-5960 3850);
FORCEPROP 1 LAST MATERIAL CHIP
J 0
(-5960 3800);
DISPLAY 0.978723 (-5960 3800);
FORCEPROP 1 LAST $LOCATION R1493
J 0
(-5955 4000);
DISPLAY 0.978723 (-5955 4000);
FORCEPROP 1 LASTPIN (-6000 3975) $PN 1
J 0
(-5995 3937);
DISPLAY 0.787234 (-5995 3937);
PAINT MONO (-5995 3937);
FORCEPROP 1 LASTPIN (-6000 3775) $PN 2
J 0
(-5995 3785);
DISPLAY 0.787234 (-5995 3785);
PAINT MONO (-5995 3785);
FORCEPROP 1 LAST PATH I191
J 0
(-5950 4050);
DISPLAY 0.978723 (-5950 4050);
PAINT WHITE (-5950 4050);
DISPLAY INVISIBLE (-5950 4050);
FORCEPROP 2 LAST CDS_LIB pure_quanta
J 0
(-6000 3875);
PAINT MONO (-6000 3875);
DISPLAY INVISIBLE (-6000 3875);
FORCEPROP 2 LAST CDS_LOCATION R1493
J 0
(-6050 4075);
DISPLAY 1.021277 (-6050 4075);
DISPLAY INVISIBLE (-6050 4075);
FORCEPROP 0 LAST $SEC 1
J 0
(-5950 4050);
DISPLAY 0.680851 (-5950 4050);
PAINT MONO (-5950 4050);
DISPLAY INVISIBLE (-5950 4050);
FORCEPROP 2 LAST CDS_SEC 1
J 0
(-6050 4075);
DISPLAY 1.021277 (-6050 4075);
DISPLAY INVISIBLE (-6050 4075);
FORCEADD OFFPAGE..1
(-6075 3575);
FORCEPROP 2 LAST $XR0 215 
J 0
(-6327 3575);
DISPLAY 0.638298 (-6327 3575);
PAINT MONO (-6327 3575);
FORCEPROP 2 LAST PATH I192
J 0
(-6350 3625);
DISPLAY 1.021277 (-6350 3625);
DISPLAY INVISIBLE (-6350 3625);
FORCEPROP 1 LAST COMMENT_BODY TRUE
J 0
(-5950 3475);
DISPLAY 0.872340 (-5950 3475);
PAINT GREEN (-5950 3475);
DISPLAY INVISIBLE (-5950 3475);
FORCEPROP 1 LAST OFFPAGE TRUE
J 0
(-5750 3450);
DISPLAY 0.872340 (-5750 3450);
DISPLAY INVISIBLE (-5750 3450);
FORCEPROP 2 LAST CDS_LIB standard
J 0
(-6075 3575);
PAINT MONO (-6075 3575);
DISPLAY INVISIBLE (-6075 3575);
FORCEADD OFFPAGE..1
(-1950 -1575);
FORCEPROP 2 LAST $XR0 215 
J 0
(-2202 -1575);
DISPLAY 0.638298 (-2202 -1575);
PAINT MONO (-2202 -1575);
FORCEPROP 2 LAST CDS_LIB standard
J 0
(-1950 -1575);
DISPLAY INVISIBLE (-1950 -1575);
FORCEPROP 2 LAST PATH I193
J 0
(-1900 -1500);
DISPLAY 1.021277 (-1900 -1500);
DISPLAY INVISIBLE (-1900 -1500);
FORCEPROP 1 LAST OFFPAGE TRUE
J 0
(-1625 -1700);
DISPLAY 0.872340 (-1625 -1700);
DISPLAY INVISIBLE (-1625 -1700);
FORCEPROP 1 LAST COMMENT_BODY TRUE
J 0
(-1825 -1675);
DISPLAY 1.170213 (-1825 -1675);
PAINT GREEN (-1825 -1675);
DISPLAY INVISIBLE (-1825 -1675);
FORCEADD OFFPAGE..2
(-75 1550);
FORCEPROP 2 LAST $XR0 215 
J 0
(114 1550);
DISPLAY 0.638298 (114 1550);
PAINT MONO (114 1550);
FORCEPROP 2 LAST CDS_LIB standard
J 0
(-75 1550);
DISPLAY INVISIBLE (-75 1550);
FORCEPROP 2 LAST PATH I194
J 0
(100 1625);
DISPLAY 1.021277 (100 1625);
DISPLAY INVISIBLE (100 1625);
FORCEPROP 1 LAST OFFPAGE TRUE
J 0
(250 1425);
DISPLAY 1.170213 (250 1425);
PAINT GREEN (250 1425);
DISPLAY INVISIBLE (250 1425);
FORCEPROP 1 LAST COMMENT_BODY TRUE
J 0
(-120 1455);
DISPLAY 1.170213 (-120 1455);
PAINT GREEN (-120 1455);
DISPLAY INVISIBLE (-120 1455);
FORCEADD UNIVERSAL_POWER..1
(975 3900);
FORCEPROP 3 LASTPIN (975 3850) SIG_NAME P3V3_AUX\g
J 0
(985 3860);
DISPLAY 0.659574 (985 3860);
PAINT MONO (985 3860);
DISPLAY INVISIBLE (985 3860);
FORCEPROP 1 LAST HDL_POWER P3V3_AUX
J 1
(975 3950);
DISPLAY 0.872340 (975 3950);
PAINT GREEN (975 3950);
FORCEPROP 1 LAST PATH I2
J 0
(1025 3925);
DISPLAY 0.872340 (1025 3925);
PAINT AQUA (1025 3925);
DISPLAY INVISIBLE (1025 3925);
FORCEPROP 2 LAST CDS_LIB logical_power
J 0
(975 3900);
PAINT MONO (975 3900);
DISPLAY INVISIBLE (975 3900);
FORCEADD OFFPAGE..2
(-75 2900);
FORCEPROP 2 LAST $XR0 183 
J 0
(114 2900);
DISPLAY 0.638298 (114 2900);
PAINT MONO (114 2900);
FORCEPROP 2 LAST PATH I20
J 0
(125 2950);
DISPLAY 1.021277 (125 2950);
DISPLAY INVISIBLE (125 2950);
FORCEPROP 1 LAST OFFPAGE TRUE
J 0
(250 2775);
DISPLAY 1.170213 (250 2775);
PAINT GREEN (250 2775);
DISPLAY INVISIBLE (250 2775);
FORCEPROP 1 LAST COMMENT_BODY TRUE
J 0
(-120 2805);
DISPLAY 1.170213 (-120 2805);
PAINT GREEN (-120 2805);
DISPLAY INVISIBLE (-120 2805);
FORCEPROP 2 LAST CDS_LIB standard
J 0
(-75 2900);
DISPLAY INVISIBLE (-75 2900);
FORCEADD OFFPAGE..2
(-75 2850);
FORCEPROP 2 LAST $XR0 229 
J 0
(114 2850);
DISPLAY 0.638298 (114 2850);
PAINT MONO (114 2850);
FORCEPROP 2 LAST PATH I21
J 0
(125 2900);
DISPLAY 1.021277 (125 2900);
DISPLAY INVISIBLE (125 2900);
FORCEPROP 1 LAST OFFPAGE TRUE
J 0
(250 2725);
DISPLAY 1.170213 (250 2725);
PAINT GREEN (250 2725);
DISPLAY INVISIBLE (250 2725);
FORCEPROP 1 LAST COMMENT_BODY TRUE
J 0
(-120 2755);
DISPLAY 1.170213 (-120 2755);
PAINT GREEN (-120 2755);
DISPLAY INVISIBLE (-120 2755);
FORCEPROP 2 LAST CDS_LIB standard
J 0
(-75 2850);
DISPLAY INVISIBLE (-75 2850);
FORCEADD OFFPAGE..1
R 2
(-75 1500);
FORCEPROP 2 LAST $XR0 224 
J 0
(111 1500);
DISPLAY 0.638298 (111 1500);
PAINT MONO (111 1500);
FORCEPROP 2 LAST CDS_LIB standard
J 0
(-75 1500);
DISPLAY INVISIBLE (-75 1500);
FORCEPROP 2 LAST PATH I212
J 0
(100 1575);
DISPLAY 1.021277 (100 1575);
DISPLAY INVISIBLE (100 1575);
FORCEPROP 1 LAST COMMENT_BODY TRUE
J 2
(-200 1400);
DISPLAY 1.170213 (-200 1400);
PAINT GREEN (-200 1400);
DISPLAY INVISIBLE (-200 1400);
FORCEPROP 1 LAST OFFPAGE TRUE
J 2
(-400 1375);
DISPLAY 0.872340 (-400 1375);
DISPLAY INVISIBLE (-400 1375);
FORCEADD Q_RES..1
(-4550 -1775);
FORCEPROP 1 LAST PART_NUMBER CS03322FB03
J 0
(-4700 -1700);
DISPLAY 0.638298 (-4700 -1700);
DISPLAY INVISIBLE (-4700 -1700);
FORCEPROP 1 LAST VALUE 33.2
J 2
(-4300 -1775);
DISPLAY 0.638298 (-4300 -1775);
FORCEPROP 1 LAST MATERIAL CHIP
J 0
(-4200 -1775);
DISPLAY 0.638298 (-4200 -1775);
FORCEPROP 1 LAST TOLERANCE 1%
J 0
(-4275 -1775);
DISPLAY 0.638298 (-4275 -1775);
FORCEPROP 1 LAST $LOCATION R4723
J 0
(-4825 -1775);
DISPLAY 0.787234 (-4825 -1775);
FORCEPROP 1 LASTPIN (-4650 -1775) $PN 1
J 0
(-4638 -1763);
DISPLAY 0.787234 (-4638 -1763);
PAINT MONO (-4638 -1763);
FORCEPROP 1 LASTPIN (-4450 -1775) $PN 2
J 0
(-4488 -1763);
DISPLAY 0.787234 (-4488 -1763);
PAINT MONO (-4488 -1763);
FORCEPROP 1 LAST PACK_TYPE 0402LF
J 0
(-4700 -1650);
DISPLAY 0.638298 (-4700 -1650);
DISPLAY INVISIBLE (-4700 -1650);
FORCEPROP 1 LAST WATTAGE 1/16W
J 2
(-4350 -1650);
DISPLAY 0.638298 (-4350 -1650);
DISPLAY INVISIBLE (-4350 -1650);
FORCEPROP 1 LAST PATH I213
J 0
(-4600 -1625);
DISPLAY 0.978723 (-4600 -1625);
PAINT WHITE (-4600 -1625);
DISPLAY INVISIBLE (-4600 -1625);
FORCEPROP 2 LAST CDS_LIB pure_quanta
J 0
(-4550 -1775);
DISPLAY INVISIBLE (-4550 -1775);
FORCEPROP 0 LAST CDS_LOCATION R4723
J 0
(-4600 -1675);
DISPLAY 1.021277 (-4600 -1675);
DISPLAY INVISIBLE (-4600 -1675);
FORCEPROP 0 LAST $SEC 1
J 0
(-4600 -1675);
DISPLAY 0.680851 (-4600 -1675);
PAINT MONO (-4600 -1675);
DISPLAY INVISIBLE (-4600 -1675);
FORCEPROP 0 LAST CDS_SEC 1
J 0
(-4600 -1675);
DISPLAY 1.021277 (-4600 -1675);
DISPLAY INVISIBLE (-4600 -1675);
FORCEADD OFFPAGE..1
(-5775 -1775);
FORCEPROP 2 LAST $XR0 184 
J 0
(-6027 -1775);
DISPLAY 0.638298 (-6027 -1775);
PAINT MONO (-6027 -1775);
FORCEPROP 1 LAST OFFPAGE TRUE
J 0
(-5450 -1900);
DISPLAY 0.872340 (-5450 -1900);
DISPLAY INVISIBLE (-5450 -1900);
FORCEPROP 1 LAST COMMENT_BODY TRUE
J 0
(-5650 -1875);
DISPLAY 1.170213 (-5650 -1875);
PAINT GREEN (-5650 -1875);
DISPLAY INVISIBLE (-5650 -1875);
FORCEPROP 2 LAST PATH I214
J 0
(-5725 -1700);
DISPLAY 1.021277 (-5725 -1700);
DISPLAY INVISIBLE (-5725 -1700);
FORCEPROP 2 LAST CDS_LIB standard
J 0
(-5775 -1775);
DISPLAY INVISIBLE (-5775 -1775);
FORCEADD OFFPAGE..2
(-3175 -1775);
FORCEPROP 2 LAST $XR0 215 
J 0
(-2986 -1775);
DISPLAY 0.638298 (-2986 -1775);
PAINT MONO (-2986 -1775);
FORCEPROP 1 LAST COMMENT_BODY TRUE
J 0
(-3220 -1870);
DISPLAY 0.872340 (-3220 -1870);
PAINT PEACH (-3220 -1870);
DISPLAY INVISIBLE (-3220 -1870);
FORCEPROP 1 LAST OFFPAGE TRUE
J 0
(-2850 -1900);
DISPLAY 0.872340 (-2850 -1900);
PAINT GREEN (-2850 -1900);
DISPLAY INVISIBLE (-2850 -1900);
FORCEPROP 2 LAST PATH I215
J 0
(-3000 -1700);
DISPLAY 1.021277 (-3000 -1700);
DISPLAY INVISIBLE (-3000 -1700);
FORCEPROP 2 LAST CDS_LIB standard
J 0
(-3175 -1775);
DISPLAY INVISIBLE (-3175 -1775);
FORCEADD OFFPAGE..1
(-3950 1900);
FORCEPROP 2 LAST $XR0 215 
J 0
(-4202 1900);
DISPLAY 0.638298 (-4202 1900);
PAINT MONO (-4202 1900);
FORCEPROP 2 LAST CDS_LIB standard
J 0
(-3950 1900);
DISPLAY INVISIBLE (-3950 1900);
FORCEPROP 2 LAST PATH I216
J 0
(-3900 1975);
DISPLAY 1.021277 (-3900 1975);
DISPLAY INVISIBLE (-3900 1975);
FORCEPROP 1 LAST COMMENT_BODY TRUE
J 0
(-3825 1800);
DISPLAY 1.170213 (-3825 1800);
PAINT GREEN (-3825 1800);
DISPLAY INVISIBLE (-3825 1800);
FORCEPROP 1 LAST OFFPAGE TRUE
J 0
(-3625 1775);
DISPLAY 0.872340 (-3625 1775);
DISPLAY INVISIBLE (-3625 1775);
FORCEADD Q_RES..1
(-4550 700);
FORCEPROP 1 LAST PART_NUMBER CS03322FB03
J 0
(-4700 775);
DISPLAY 0.638298 (-4700 775);
DISPLAY INVISIBLE (-4700 775);
FORCEPROP 1 LAST MATERIAL CHIP
J 0
(-4200 700);
DISPLAY 0.638298 (-4200 700);
FORCEPROP 1 LAST VALUE 33.2
J 2
(-4300 700);
DISPLAY 0.638298 (-4300 700);
FORCEPROP 1 LAST TOLERANCE 1%
J 0
(-4275 700);
DISPLAY 0.638298 (-4275 700);
FORCEPROP 1 LAST LOCATION R4057
J 0
(-4800 700);
DISPLAY 0.638298 (-4800 700);
FORCEPROP 1 LASTPIN (-4650 700) $PN 1
J 0
(-4638 712);
DISPLAY 0.787234 (-4638 712);
PAINT MONO (-4638 712);
FORCEPROP 1 LASTPIN (-4450 700) $PN 2
J 0
(-4488 712);
DISPLAY 0.787234 (-4488 712);
PAINT MONO (-4488 712);
FORCEPROP 1 LAST WATTAGE 1/16W
J 2
(-4350 825);
DISPLAY 0.638298 (-4350 825);
DISPLAY INVISIBLE (-4350 825);
FORCEPROP 1 LAST PACK_TYPE 0402LF
J 0
(-4700 825);
DISPLAY 0.638298 (-4700 825);
DISPLAY INVISIBLE (-4700 825);
FORCEPROP 1 LAST PATH I217
J 0
(-4600 850);
DISPLAY 0.978723 (-4600 850);
PAINT WHITE (-4600 850);
DISPLAY INVISIBLE (-4600 850);
FORCEPROP 2 LAST CDS_LIB pure_quanta
J 0
(-4550 700);
DISPLAY INVISIBLE (-4550 700);
FORCEPROP 0 LAST $SEC 1
J 0
(-4200 750);
DISPLAY 0.680851 (-4200 750);
PAINT MONO (-4200 750);
DISPLAY INVISIBLE (-4200 750);
FORCEPROP 0 LAST CDS_SEC 1
J 0
(-4200 750);
DISPLAY 1.021277 (-4200 750);
DISPLAY INVISIBLE (-4200 750);
FORCEADD OFFPAGE..1
R 2
(-75 2750);
FORCEPROP 2 LAST $XR0 205 
J 0
(111 2750);
DISPLAY 0.638298 (111 2750);
PAINT MONO (111 2750);
FORCEPROP 2 LAST PATH I23
J 0
(125 2800);
DISPLAY 1.021277 (125 2800);
DISPLAY INVISIBLE (125 2800);
FORCEPROP 2 LAST CDS_LIB standard
J 0
(-75 2750);
PAINT MONO (-75 2750);
DISPLAY INVISIBLE (-75 2750);
FORCEPROP 1 LAST OFFPAGE TRUE
J 2
(-400 2625);
DISPLAY 1.170213 (-400 2625);
PAINT GREEN (-400 2625);
DISPLAY INVISIBLE (-400 2625);
FORCEPROP 1 LAST COMMENT_BODY TRUE
J 2
(-200 2650);
DISPLAY 1.170213 (-200 2650);
PAINT GREEN (-200 2650);
DISPLAY INVISIBLE (-200 2650);
FORCEADD OFFPAGE..1
R 2
(-75 2700);
FORCEPROP 2 LAST $XR0 220 
J 0
(111 2700);
DISPLAY 0.638298 (111 2700);
PAINT MONO (111 2700);
FORCEPROP 2 LAST PATH I24
J 0
(125 2750);
DISPLAY 1.021277 (125 2750);
DISPLAY INVISIBLE (125 2750);
FORCEPROP 1 LAST OFFPAGE TRUE
J 2
(-400 2575);
DISPLAY 1.170213 (-400 2575);
PAINT GREEN (-400 2575);
DISPLAY INVISIBLE (-400 2575);
FORCEPROP 1 LAST COMMENT_BODY TRUE
J 2
(-200 2600);
DISPLAY 1.170213 (-200 2600);
PAINT GREEN (-200 2600);
DISPLAY INVISIBLE (-200 2600);
FORCEPROP 2 LAST CDS_LIB standard
J 0
(-75 2700);
DISPLAY INVISIBLE (-75 2700);
FORCEADD OFFPAGE..1
R 2
(-75 2650);
FORCEPROP 2 LAST $XR0 240 
J 0
(111 2650);
DISPLAY 0.638298 (111 2650);
PAINT MONO (111 2650);
FORCEPROP 2 LAST PATH I25
J 0
(125 2700);
DISPLAY 1.021277 (125 2700);
DISPLAY INVISIBLE (125 2700);
FORCEPROP 1 LAST COMMENT_BODY TRUE
J 2
(-200 2550);
DISPLAY 1.170213 (-200 2550);
PAINT GREEN (-200 2550);
DISPLAY INVISIBLE (-200 2550);
FORCEPROP 1 LAST OFFPAGE TRUE
J 2
(-400 2525);
DISPLAY 1.170213 (-400 2525);
PAINT GREEN (-400 2525);
DISPLAY INVISIBLE (-400 2525);
FORCEPROP 2 LAST CDS_LIB standard
J 0
(-75 2650);
DISPLAY INVISIBLE (-75 2650);
FORCEADD OFFPAGE..1
R 2
(-75 2600);
FORCEPROP 2 LAST $XR0 205 
J 0
(111 2600);
DISPLAY 0.638298 (111 2600);
PAINT MONO (111 2600);
FORCEPROP 2 LAST PATH I26
J 0
(125 2650);
DISPLAY 1.021277 (125 2650);
DISPLAY INVISIBLE (125 2650);
FORCEPROP 1 LAST COMMENT_BODY TRUE
J 2
(-200 2500);
DISPLAY 1.170213 (-200 2500);
PAINT GREEN (-200 2500);
DISPLAY INVISIBLE (-200 2500);
FORCEPROP 1 LAST OFFPAGE TRUE
J 2
(-400 2475);
DISPLAY 1.170213 (-400 2475);
PAINT GREEN (-400 2475);
DISPLAY INVISIBLE (-400 2475);
FORCEPROP 2 LAST CDS_LIB standard
J 0
(-75 2600);
DISPLAY INVISIBLE (-75 2600);
FORCEADD OFFPAGE..1
R 2
(-75 2550);
FORCEPROP 2 LAST $XR1 220 
J 0
(231 2550);
DISPLAY 0.638298 (231 2550);
PAINT MONO (231 2550);
FORCEPROP 2 LAST $XR0 240 
J 0
(111 2550);
DISPLAY 0.638298 (111 2550);
PAINT MONO (111 2550);
FORCEPROP 2 LAST PATH I27
J 0
(250 2600);
DISPLAY 1.021277 (250 2600);
DISPLAY INVISIBLE (250 2600);
FORCEPROP 1 LAST COMMENT_BODY TRUE
J 2
(-200 2450);
DISPLAY 1.170213 (-200 2450);
PAINT GREEN (-200 2450);
DISPLAY INVISIBLE (-200 2450);
FORCEPROP 1 LAST OFFPAGE TRUE
J 2
(-400 2425);
DISPLAY 1.170213 (-400 2425);
PAINT GREEN (-400 2425);
DISPLAY INVISIBLE (-400 2425);
FORCEPROP 2 LAST CDS_LIB standard
J 0
(-75 2550);
DISPLAY INVISIBLE (-75 2550);
FORCEADD OFFPAGE..1
R 2
(-75 2500);
FORCEPROP 2 LAST $XR0 223 
J 0
(111 2500);
DISPLAY 0.638298 (111 2500);
PAINT MONO (111 2500);
FORCEPROP 2 LAST PATH I28
J 0
(125 2550);
DISPLAY 1.021277 (125 2550);
DISPLAY INVISIBLE (125 2550);
FORCEPROP 1 LAST COMMENT_BODY TRUE
J 2
(-200 2400);
DISPLAY 1.170213 (-200 2400);
PAINT GREEN (-200 2400);
DISPLAY INVISIBLE (-200 2400);
FORCEPROP 1 LAST OFFPAGE TRUE
J 2
(-400 2375);
DISPLAY 0.872340 (-400 2375);
DISPLAY INVISIBLE (-400 2375);
FORCEPROP 2 LAST CDS_LIB standard
J 2
(-75 2500);
DISPLAY INVISIBLE (-75 2500);
FORCEADD OFFPAGE..1
R 2
(-75 2450);
FORCEPROP 2 LAST $XR0 183 
J 0
(111 2450);
DISPLAY 0.638298 (111 2450);
PAINT MONO (111 2450);
FORCEPROP 2 LAST PATH I29
J 0
(125 2500);
DISPLAY 1.021277 (125 2500);
DISPLAY INVISIBLE (125 2500);
FORCEPROP 1 LAST COMMENT_BODY TRUE
J 2
(-200 2350);
DISPLAY 1.170213 (-200 2350);
PAINT GREEN (-200 2350);
DISPLAY INVISIBLE (-200 2350);
FORCEPROP 1 LAST OFFPAGE TRUE
J 2
(-400 2325);
DISPLAY 1.170213 (-400 2325);
PAINT GREEN (-400 2325);
DISPLAY INVISIBLE (-400 2325);
FORCEPROP 2 LAST CDS_LIB standard
J 0
(-75 2450);
PAINT MONO (-75 2450);
DISPLAY INVISIBLE (-75 2450);
FORCEADD Q_RES..2
(975 3650);
FORCEPROP 1 LAST PART_NUMBER CS31002FB08
J 0
(1015 3525);
DISPLAY 0.638298 (1015 3525);
DISPLAY INVISIBLE (1015 3525);
FORCEPROP 1 LAST PACK_TYPE 0402LF
J 0
(1015 3475);
DISPLAY 0.638298 (1015 3475);
FORCEPROP 1 LAST MATERIAL EMPTY
J 0
(1015 3575);
DISPLAY 0.638298 (1015 3575);
PAINT RED (1015 3575);
FORCEPROP 1 LAST WATTAGE 1/16W
J 0
(1015 3625);
DISPLAY 0.638298 (1015 3625);
FORCEPROP 1 LAST TOLERANCE 1%
J 0
(1020 3675);
DISPLAY 0.638298 (1020 3675);
FORCEPROP 1 LAST VALUE 10K
J 0
(1020 3725);
DISPLAY 0.638298 (1020 3725);
FORCEPROP 1 LAST $LOCATION R1465
J 0
(1020 3775);
DISPLAY 0.638298 (1020 3775);
FORCEPROP 1 LASTPIN (975 3750) $PN 1
J 0
(980 3712);
DISPLAY 0.787234 (980 3712);
FORCEPROP 1 LASTPIN (975 3550) $PN 2
J 0
(980 3560);
DISPLAY 0.787234 (980 3560);
FORCEPROP 1 LAST PATH I3
J 0
(1025 3825);
DISPLAY 0.978723 (1025 3825);
PAINT WHITE (1025 3825);
DISPLAY INVISIBLE (1025 3825);
FORCEPROP 2 LAST CDS_LIB pure_quanta
J 0
(975 3650);
PAINT MONO (975 3650);
DISPLAY INVISIBLE (975 3650);
FORCEPROP 2 LAST CDS_LOCATION R1465
J 2
(1025 3875);
DISPLAY 1.021277 (1025 3875);
DISPLAY INVISIBLE (1025 3875);
FORCEPROP 2 LAST $SEC 1
J 2
(1025 3875);
DISPLAY 0.680851 (1025 3875);
PAINT MONO (1025 3875);
DISPLAY INVISIBLE (1025 3875);
FORCEPROP 2 LAST CDS_SEC 1
J 2
(1025 3875);
DISPLAY 1.021277 (1025 3875);
DISPLAY INVISIBLE (1025 3875);
FORCEADD OFFPAGE..2
(-75 2400);
FORCEPROP 2 LAST $XR0 215 
J 0
(114 2400);
DISPLAY 0.638298 (114 2400);
PAINT MONO (114 2400);
FORCEPROP 2 LAST PATH I30
J 0
(125 2450);
DISPLAY 1.021277 (125 2450);
DISPLAY INVISIBLE (125 2450);
FORCEPROP 1 LAST COMMENT_BODY TRUE
J 0
(-120 2305);
DISPLAY 1.170213 (-120 2305);
PAINT GREEN (-120 2305);
DISPLAY INVISIBLE (-120 2305);
FORCEPROP 1 LAST OFFPAGE TRUE
J 0
(250 2275);
DISPLAY 1.170213 (250 2275);
PAINT GREEN (250 2275);
DISPLAY INVISIBLE (250 2275);
FORCEPROP 2 LAST CDS_LIB standard
J 0
(-75 2400);
DISPLAY INVISIBLE (-75 2400);
FORCEADD OFFPAGE..1
R 2
(-75 2350);
FORCEPROP 2 LAST $XR0 223 
J 0
(111 2350);
DISPLAY 0.638298 (111 2350);
PAINT MONO (111 2350);
FORCEPROP 1 LAST COMMENT_BODY TRUE
J 2
(-200 2250);
DISPLAY 1.170213 (-200 2250);
PAINT GREEN (-200 2250);
DISPLAY INVISIBLE (-200 2250);
FORCEPROP 1 LAST OFFPAGE TRUE
J 2
(-400 2225);
DISPLAY 0.872340 (-400 2225);
DISPLAY INVISIBLE (-400 2225);
FORCEPROP 2 LAST PATH I31
J 0
(125 2400);
DISPLAY 1.021277 (125 2400);
DISPLAY INVISIBLE (125 2400);
FORCEPROP 2 LAST CDS_LIB standard
J 2
(-75 2350);
DISPLAY INVISIBLE (-75 2350);
FORCEADD OFFPAGE..5
R 2
(-75 2300);
FORCEPROP 2 LAST $XR2 252 
J 0
(354 2300);
DISPLAY 0.638298 (354 2300);
PAINT MONO (354 2300);
FORCEPROP 2 LAST $XR1 223 
J 0
(234 2300);
DISPLAY 0.638298 (234 2300);
PAINT MONO (234 2300);
FORCEPROP 2 LAST $XR0 219 
J 0
(114 2300);
DISPLAY 0.638298 (114 2300);
PAINT MONO (114 2300);
FORCEPROP 2 LAST PATH I32
J 0
(375 2350);
DISPLAY 1.021277 (375 2350);
DISPLAY INVISIBLE (375 2350);
FORCEPROP 2 LAST CDS_LIB standard
J 2
(-75 2300);
DISPLAY INVISIBLE (-75 2300);
FORCEPROP 1 LAST OFFPAGE TRUE
J 2
(-400 2175);
DISPLAY 0.872340 (-400 2175);
DISPLAY INVISIBLE (-400 2175);
FORCEPROP 1 LAST COMMENT_BODY TRUE
J 2
(-175 2225);
DISPLAY 1.170213 (-175 2225);
PAINT GREEN (-175 2225);
DISPLAY INVISIBLE (-175 2225);
FORCEADD OFFPAGE..2
(-75 2250);
FORCEPROP 2 LAST $XR0 239 
J 0
(114 2250);
DISPLAY 0.638298 (114 2250);
PAINT MONO (114 2250);
FORCEPROP 2 LAST PATH I34
J 0
(125 2300);
DISPLAY 1.021277 (125 2300);
DISPLAY INVISIBLE (125 2300);
FORCEPROP 1 LAST OFFPAGE TRUE
J 0
(250 2125);
DISPLAY 1.170213 (250 2125);
PAINT GREEN (250 2125);
DISPLAY INVISIBLE (250 2125);
FORCEPROP 1 LAST COMMENT_BODY TRUE
J 0
(-120 2155);
DISPLAY 1.170213 (-120 2155);
PAINT GREEN (-120 2155);
DISPLAY INVISIBLE (-120 2155);
FORCEPROP 2 LAST CDS_LIB standard
J 0
(-75 2250);
DISPLAY INVISIBLE (-75 2250);
FORCEADD OFFPAGE..2
(-75 2050);
FORCEPROP 2 LAST $XR0 212 
J 0
(114 2050);
DISPLAY 0.638298 (114 2050);
PAINT MONO (114 2050);
FORCEPROP 2 LAST CDS_LIB standard
J 0
(-75 2050);
DISPLAY INVISIBLE (-75 2050);
FORCEPROP 2 LAST PATH I36
J 0
(125 2100);
DISPLAY 1.021277 (125 2100);
DISPLAY INVISIBLE (125 2100);
FORCEPROP 1 LAST COMMENT_BODY TRUE
J 0
(-120 1955);
DISPLAY 1.170213 (-120 1955);
PAINT GREEN (-120 1955);
DISPLAY INVISIBLE (-120 1955);
FORCEPROP 1 LAST OFFPAGE TRUE
J 0
(250 1925);
DISPLAY 1.170213 (250 1925);
PAINT GREEN (250 1925);
DISPLAY INVISIBLE (250 1925);
FORCEADD OFFPAGE..2
(-75 2100);
FORCEPROP 2 LAST $XR0 206 
J 0
(114 2100);
DISPLAY 0.638298 (114 2100);
PAINT MONO (114 2100);
FORCEPROP 1 LAST OFFPAGE TRUE
J 0
(250 1975);
DISPLAY 1.170213 (250 1975);
PAINT GREEN (250 1975);
DISPLAY INVISIBLE (250 1975);
FORCEPROP 1 LAST COMMENT_BODY TRUE
J 0
(-120 2005);
DISPLAY 1.170213 (-120 2005);
PAINT GREEN (-120 2005);
DISPLAY INVISIBLE (-120 2005);
FORCEPROP 2 LAST PATH I37
J 0
(125 2150);
DISPLAY 1.021277 (125 2150);
DISPLAY INVISIBLE (125 2150);
FORCEPROP 2 LAST CDS_LIB standard
J 0
(-75 2100);
DISPLAY INVISIBLE (-75 2100);
FORCEADD Q_RES..1
(950 2375);
FORCEPROP 1 LAST PART_NUMBER CS04992FB07
J 0
(800 2300);
DISPLAY 0.638298 (800 2300);
DISPLAY INVISIBLE (800 2300);
FORCEPROP 1 LAST VALUE 49.9
J 2
(1200 2375);
DISPLAY 0.638298 (1200 2375);
FORCEPROP 1 LAST MATERIAL CHIP
J 0
(1175 2325);
DISPLAY 0.638298 (1175 2325);
FORCEPROP 1 LAST TOLERANCE 1%
J 0
(1225 2375);
DISPLAY 0.638298 (1225 2375);
FORCEPROP 1 LAST PACK_TYPE 0402LF
J 0
(800 2250);
DISPLAY 0.638298 (800 2250);
FORCEPROP 1 LAST WATTAGE 1/16W
J 2
(1150 2250);
DISPLAY 0.638298 (1150 2250);
FORCEPROP 1 LAST $LOCATION R1710
J 0
(675 2375);
DISPLAY 0.638298 (675 2375);
FORCEPROP 1 LASTPIN (850 2375) $PN 1
J 0
(862 2387);
DISPLAY 0.787234 (862 2387);
FORCEPROP 1 LASTPIN (1050 2375) $PN 2
J 0
(1012 2387);
DISPLAY 0.787234 (1012 2387);
FORCEPROP 1 LAST PATH I38
J 0
(900 2525);
DISPLAY 0.978723 (900 2525);
PAINT WHITE (900 2525);
DISPLAY INVISIBLE (900 2525);
FORCEPROP 2 LAST CDS_LIB pure_quanta
J 0
(950 2375);
PAINT MONO (950 2375);
DISPLAY INVISIBLE (950 2375);
FORCEPROP 2 LAST CDS_LOCATION R1710
J 0
(900 2575);
DISPLAY 1.021277 (900 2575);
DISPLAY INVISIBLE (900 2575);
FORCEPROP 2 LAST $SEC 1
J 0
(900 2575);
DISPLAY 0.680851 (900 2575);
PAINT MONO (900 2575);
DISPLAY INVISIBLE (900 2575);
FORCEPROP 2 LAST CDS_SEC 1
J 0
(900 2575);
DISPLAY 1.021277 (900 2575);
DISPLAY INVISIBLE (900 2575);
FORCEADD Q_CAP..1
R 2
(775 2050);
FORCEPROP 1 LAST PART_NUMBER CH4104K1B00
J 2
(725 1900);
DISPLAY 0.638298 (725 1900);
DISPLAY INVISIBLE (725 1900);
FORCEPROP 1 LAST VALUE 0.1UF
J 2
(725 2100);
DISPLAY 0.638298 (725 2100);
FORCEPROP 1 LAST MATERIAL X7R
J 2
(725 1950);
DISPLAY 0.638298 (725 1950);
FORCEPROP 1 LAST TOLERANCE 10%
J 2
(725 2000);
DISPLAY 0.638298 (725 2000);
FORCEPROP 1 LAST VOLTAGE 25V
J 2
(725 2050);
DISPLAY 0.638298 (725 2050);
FORCEPROP 1 LAST PACK_TYPE 0402
J 2
(725 1850);
DISPLAY 0.638298 (725 1850);
FORCEPROP 1 LAST $LOCATION C1325
J 2
(725 2150);
DISPLAY 0.787234 (725 2150);
FORCEPROP 1 LASTPIN (775 2150) $PN 1
J 2
(765 2130);
DISPLAY 0.787234 (765 2130);
FORCEPROP 1 LASTPIN (775 1950) $PN 2
J 2
(765 1930);
DISPLAY 0.787234 (765 1930);
FORCEPROP 1 LAST PATH I39
J 2
(725 2200);
DISPLAY 0.978723 (725 2200);
PAINT WHITE (725 2200);
DISPLAY INVISIBLE (725 2200);
FORCEPROP 2 LAST CDS_LIB pure_quanta
J 2
(775 2050);
PAINT MONO (775 2050);
DISPLAY INVISIBLE (775 2050);
FORCEPROP 2 LAST CDS_LOCATION C1325
J 2
(725 2250);
DISPLAY 1.021277 (725 2250);
DISPLAY INVISIBLE (725 2250);
FORCEPROP 2 LAST $SEC 1
J 2
(725 2250);
DISPLAY 0.680851 (725 2250);
PAINT MONO (725 2250);
DISPLAY INVISIBLE (725 2250);
FORCEPROP 2 LAST CDS_SEC 1
J 2
(725 2250);
DISPLAY 1.021277 (725 2250);
DISPLAY INVISIBLE (725 2250);
FORCEADD UNIVERSAL_POWER..1
(1775 2750);
FORCEPROP 3 LASTPIN (1775 2700) SIG_NAME P3V3_AUX\g
J 0
(1785 2710);
DISPLAY 0.659574 (1785 2710);
PAINT MONO (1785 2710);
DISPLAY INVISIBLE (1785 2710);
FORCEPROP 1 LAST HDL_POWER P3V3_AUX
J 1
(1775 2800);
DISPLAY 0.872340 (1775 2800);
PAINT GREEN (1775 2800);
FORCEPROP 1 LAST PATH I4
J 0
(1825 2775);
DISPLAY 0.872340 (1825 2775);
PAINT AQUA (1825 2775);
DISPLAY INVISIBLE (1825 2775);
FORCEPROP 2 LAST CDS_LIB logical_power
J 0
(1775 2750);
PAINT MONO (1775 2750);
DISPLAY INVISIBLE (1775 2750);
FORCEADD UNIVERSAL_GND..1
(775 1775);
FORCEPROP 3 LASTPIN (775 1825) SIG_NAME GND\g
J 0
(785 1835);
DISPLAY 0.659574 (785 1835);
PAINT MONO (785 1835);
DISPLAY INVISIBLE (785 1835);
FORCEPROP 1 LAST HDL_POWER GND
J 1
(800 1700);
DISPLAY 0.872340 (800 1700);
PAINT GREEN (800 1700);
DISPLAY INVISIBLE (800 1700);
FORCEPROP 1 LAST PATH I40
J 0
(850 1775);
DISPLAY 0.872340 (850 1775);
PAINT AQUA (850 1775);
DISPLAY INVISIBLE (850 1775);
FORCEPROP 2 LAST CDS_LIB logical_power
J 0
(775 1775);
PAINT MONO (775 1775);
DISPLAY INVISIBLE (775 1775);
FORCEADD OFFPAGE..5
(-3950 3850);
FORCEPROP 2 LAST $XR0 215 
J 0
(-4235 3850);
DISPLAY 0.638298 (-4235 3850);
PAINT MONO (-4235 3850);
FORCEPROP 2 LAST PATH I41
J 0
(-4200 3900);
DISPLAY 1.021277 (-4200 3900);
DISPLAY INVISIBLE (-4200 3900);
FORCEPROP 2 LAST CDS_LIB standard
J 0
(-3950 3850);
DISPLAY INVISIBLE (-3950 3850);
FORCEPROP 1 LAST COMMENT_BODY TRUE
J 0
(-3850 3775);
DISPLAY 1.170213 (-3850 3775);
PAINT GREEN (-3850 3775);
DISPLAY INVISIBLE (-3850 3775);
FORCEPROP 1 LAST OFFPAGE TRUE
J 0
(-3625 3725);
DISPLAY 0.872340 (-3625 3725);
DISPLAY INVISIBLE (-3625 3725);
FORCEADD OFFPAGE..1
(-3950 3800);
FORCEPROP 2 LAST $XR0 215 
J 0
(-4232 3800);
DISPLAY 0.638298 (-4232 3800);
PAINT MONO (-4232 3800);
FORCEPROP 2 LAST PATH I42
J 0
(-4200 3850);
DISPLAY 1.021277 (-4200 3850);
DISPLAY INVISIBLE (-4200 3850);
FORCEPROP 2 LAST CDS_LIB standard
J 0
(-3950 3800);
PAINT MONO (-3950 3800);
DISPLAY INVISIBLE (-3950 3800);
FORCEPROP 1 LAST OFFPAGE TRUE
J 0
(-3625 3675);
DISPLAY 0.872340 (-3625 3675);
DISPLAY INVISIBLE (-3625 3675);
FORCEPROP 1 LAST COMMENT_BODY TRUE
J 0
(-3825 3700);
DISPLAY 1.170213 (-3825 3700);
PAINT GREEN (-3825 3700);
DISPLAY INVISIBLE (-3825 3700);
FORCEADD OFFPAGE..1
(-3950 3700);
FORCEPROP 2 LAST $XR1 201 
J 0
(-4322 3700);
DISPLAY 0.638298 (-4322 3700);
PAINT MONO (-4322 3700);
FORCEPROP 2 LAST $XR0 183 
J 0
(-4202 3700);
DISPLAY 0.638298 (-4202 3700);
PAINT MONO (-4202 3700);
FORCEPROP 2 LAST PATH I43
J 0
(-4200 3750);
DISPLAY 1.021277 (-4200 3750);
DISPLAY INVISIBLE (-4200 3750);
FORCEPROP 2 LAST CDS_LIB standard
J 2
(-3950 3700);
PAINT MONO (-3950 3700);
DISPLAY INVISIBLE (-3950 3700);
FORCEPROP 1 LAST OFFPAGE TRUE
J 0
(-3625 3575);
DISPLAY 1.170213 (-3625 3575);
PAINT GREEN (-3625 3575);
DISPLAY INVISIBLE (-3625 3575);
FORCEPROP 1 LAST COMMENT_BODY TRUE
J 0
(-3825 3600);
DISPLAY 1.170213 (-3825 3600);
PAINT GREEN (-3825 3600);
DISPLAY INVISIBLE (-3825 3600);
FORCEADD OFFPAGE..1
(-3950 3750);
FORCEPROP 2 LAST $XR1 220 
J 0
(-4322 3750);
DISPLAY 0.638298 (-4322 3750);
PAINT MONO (-4322 3750);
FORCEPROP 2 LAST $XR0 205 
J 0
(-4202 3750);
DISPLAY 0.638298 (-4202 3750);
PAINT MONO (-4202 3750);
FORCEPROP 2 LAST PATH I44
J 0
(-4200 3800);
DISPLAY 1.021277 (-4200 3800);
DISPLAY INVISIBLE (-4200 3800);
FORCEPROP 2 LAST CDS_LIB standard
J 2
(-3950 3750);
DISPLAY INVISIBLE (-3950 3750);
FORCEPROP 1 LAST OFFPAGE TRUE
J 0
(-3625 3625);
DISPLAY 1.170213 (-3625 3625);
PAINT GREEN (-3625 3625);
DISPLAY INVISIBLE (-3625 3625);
FORCEPROP 1 LAST COMMENT_BODY TRUE
J 0
(-3825 3650);
DISPLAY 1.170213 (-3825 3650);
PAINT GREEN (-3825 3650);
DISPLAY INVISIBLE (-3825 3650);
FORCEADD OFFPAGE..5
(-3950 3650);
FORCEPROP 2 LAST $XR0 205 
J 0
(-4235 3650);
DISPLAY 0.638298 (-4235 3650);
PAINT MONO (-4235 3650);
FORCEPROP 2 LAST PATH I45
J 0
(-4200 3700);
DISPLAY 1.021277 (-4200 3700);
DISPLAY INVISIBLE (-4200 3700);
FORCEPROP 1 LAST OFFPAGE TRUE
J 0
(-3625 3525);
DISPLAY 0.872340 (-3625 3525);
DISPLAY INVISIBLE (-3625 3525);
FORCEPROP 1 LAST COMMENT_BODY TRUE
J 0
(-3850 3575);
DISPLAY 1.170213 (-3850 3575);
PAINT GREEN (-3850 3575);
DISPLAY INVISIBLE (-3850 3575);
FORCEPROP 2 LAST CDS_LIB standard
J 0
(-3950 3650);
PAINT MONO (-3950 3650);
DISPLAY INVISIBLE (-3950 3650);
FORCEADD OFFPAGE..2
R 2
(-3950 3600);
FORCEPROP 2 LAST $XR0 223 
J 0
(-4235 3600);
DISPLAY 0.638298 (-4235 3600);
PAINT MONO (-4235 3600);
FORCEPROP 2 LAST PATH I46
J 0
(-4200 3650);
DISPLAY 1.021277 (-4200 3650);
DISPLAY INVISIBLE (-4200 3650);
FORCEPROP 1 LAST OFFPAGE TRUE
J 2
(-4275 3475);
DISPLAY 1.170213 (-4275 3475);
PAINT GREEN (-4275 3475);
DISPLAY INVISIBLE (-4275 3475);
FORCEPROP 1 LAST COMMENT_BODY TRUE
J 2
(-3905 3505);
DISPLAY 1.170213 (-3905 3505);
PAINT GREEN (-3905 3505);
DISPLAY INVISIBLE (-3905 3505);
FORCEPROP 2 LAST CDS_LIB standard
J 2
(-3950 3600);
DISPLAY INVISIBLE (-3950 3600);
FORCEADD OFFPAGE..1
(-3950 3550);
FORCEPROP 2 LAST $XR0 215 
J 0
(-4232 3550);
DISPLAY 0.638298 (-4232 3550);
PAINT MONO (-4232 3550);
FORCEPROP 2 LAST CDS_LIB standard
J 0
(-3950 3550);
PAINT MONO (-3950 3550);
DISPLAY INVISIBLE (-3950 3550);
FORCEPROP 2 LAST PATH I47
J 0
(-4200 3600);
DISPLAY 1.021277 (-4200 3600);
DISPLAY INVISIBLE (-4200 3600);
FORCEPROP 1 LAST COMMENT_BODY TRUE
J 0
(-3825 3450);
DISPLAY 1.170213 (-3825 3450);
PAINT GREEN (-3825 3450);
DISPLAY INVISIBLE (-3825 3450);
FORCEPROP 1 LAST OFFPAGE TRUE
J 0
(-3625 3425);
DISPLAY 0.872340 (-3625 3425);
DISPLAY INVISIBLE (-3625 3425);
FORCEADD OFFPAGE..1
(-3950 3450);
FORCEPROP 2 LAST $XR0 278 
J 0
(-4202 3450);
DISPLAY 0.638298 (-4202 3450);
PAINT MONO (-4202 3450);
FORCEPROP 2 LAST PATH I48
J 0
(-4200 3500);
DISPLAY 1.021277 (-4200 3500);
DISPLAY INVISIBLE (-4200 3500);
FORCEPROP 1 LAST COMMENT_BODY TRUE
J 0
(-3825 3350);
DISPLAY 1.170213 (-3825 3350);
PAINT GREEN (-3825 3350);
DISPLAY INVISIBLE (-3825 3350);
FORCEPROP 1 LAST OFFPAGE TRUE
J 0
(-3625 3325);
DISPLAY 0.872340 (-3625 3325);
DISPLAY INVISIBLE (-3625 3325);
FORCEPROP 2 LAST CDS_LIB standard
J 0
(-3950 3450);
DISPLAY INVISIBLE (-3950 3450);
FORCEADD Q_RES..2
(1775 2500);
FORCEPROP 1 LAST PART_NUMBER CS31002FB08
J 0
(1815 2375);
DISPLAY 0.638298 (1815 2375);
DISPLAY INVISIBLE (1815 2375);
FORCEPROP 1 LAST TOLERANCE 1%
J 0
(1820 2525);
DISPLAY 0.638298 (1820 2525);
FORCEPROP 1 LAST VALUE 10K
J 0
(1820 2575);
DISPLAY 0.638298 (1820 2575);
FORCEPROP 1 LAST WATTAGE 1/16W
J 0
(1815 2475);
DISPLAY 0.638298 (1815 2475);
FORCEPROP 1 LAST MATERIAL CHIP
J 0
(1815 2425);
DISPLAY 0.638298 (1815 2425);
FORCEPROP 1 LAST PACK_TYPE 0402LF
J 0
(1815 2325);
DISPLAY 0.638298 (1815 2325);
FORCEPROP 1 LAST $LOCATION R1106
J 0
(1820 2625);
DISPLAY 0.638298 (1820 2625);
FORCEPROP 1 LASTPIN (1775 2600) $PN 1
J 0
(1780 2562);
DISPLAY 0.787234 (1780 2562);
FORCEPROP 1 LASTPIN (1775 2400) $PN 2
J 0
(1780 2410);
DISPLAY 0.787234 (1780 2410);
FORCEPROP 1 LAST PATH I5
J 0
(1825 2675);
DISPLAY 0.978723 (1825 2675);
PAINT WHITE (1825 2675);
DISPLAY INVISIBLE (1825 2675);
FORCEPROP 2 LAST CDS_LIB pure_quanta
J 0
(1775 2500);
PAINT MONO (1775 2500);
DISPLAY INVISIBLE (1775 2500);
FORCEPROP 2 LAST CDS_LOCATION R1106
J 0
(1825 2725);
DISPLAY 1.021277 (1825 2725);
DISPLAY INVISIBLE (1825 2725);
FORCEPROP 2 LAST $SEC 1
J 0
(1825 2725);
DISPLAY 0.680851 (1825 2725);
PAINT MONO (1825 2725);
DISPLAY INVISIBLE (1825 2725);
FORCEPROP 2 LAST CDS_SEC 1
J 0
(1825 2725);
DISPLAY 1.021277 (1825 2725);
DISPLAY INVISIBLE (1825 2725);
FORCEADD OFFPAGE..5
(-3950 3400);
FORCEPROP 2 LAST $XR0 183 
J 0
(-4235 3400);
DISPLAY 0.638298 (-4235 3400);
PAINT MONO (-4235 3400);
FORCEPROP 2 LAST PATH I50
J 0
(-4200 3450);
DISPLAY 1.021277 (-4200 3450);
DISPLAY INVISIBLE (-4200 3450);
FORCEPROP 2 LAST CDS_LIB standard
J 0
(-3950 3400);
PAINT MONO (-3950 3400);
DISPLAY INVISIBLE (-3950 3400);
FORCEPROP 1 LAST COMMENT_BODY TRUE
J 0
(-3850 3325);
DISPLAY 1.170213 (-3850 3325);
PAINT GREEN (-3850 3325);
DISPLAY INVISIBLE (-3850 3325);
FORCEPROP 1 LAST OFFPAGE TRUE
J 0
(-3625 3275);
DISPLAY 0.872340 (-3625 3275);
DISPLAY INVISIBLE (-3625 3275);
FORCEADD OFFPAGE..5
(-3950 3350);
FORCEPROP 2 LAST $XR0 223 
J 0
(-4235 3350);
DISPLAY 0.638298 (-4235 3350);
PAINT MONO (-4235 3350);
FORCEPROP 2 LAST PATH I51
J 0
(-4200 3400);
DISPLAY 1.021277 (-4200 3400);
DISPLAY INVISIBLE (-4200 3400);
FORCEPROP 1 LAST COMMENT_BODY TRUE
J 0
(-3850 3275);
DISPLAY 1.170213 (-3850 3275);
PAINT GREEN (-3850 3275);
DISPLAY INVISIBLE (-3850 3275);
FORCEPROP 1 LAST OFFPAGE TRUE
J 0
(-3625 3225);
DISPLAY 0.872340 (-3625 3225);
DISPLAY INVISIBLE (-3625 3225);
FORCEPROP 2 LAST CDS_LIB standard
J 0
(-3950 3350);
DISPLAY INVISIBLE (-3950 3350);
FORCEADD OFFPAGE..5
(-3950 3300);
FORCEPROP 2 LAST $XR1 223 
J 0
(-4355 3300);
DISPLAY 0.638298 (-4355 3300);
PAINT MONO (-4355 3300);
FORCEPROP 2 LAST $XR0 219 
J 0
(-4235 3300);
DISPLAY 0.638298 (-4235 3300);
PAINT MONO (-4235 3300);
FORCEPROP 2 LAST PATH I52
J 0
(-4200 3350);
DISPLAY 1.021277 (-4200 3350);
DISPLAY INVISIBLE (-4200 3350);
FORCEPROP 1 LAST OFFPAGE TRUE
J 0
(-3625 3175);
DISPLAY 0.872340 (-3625 3175);
DISPLAY INVISIBLE (-3625 3175);
FORCEPROP 1 LAST COMMENT_BODY TRUE
J 0
(-3850 3225);
DISPLAY 1.170213 (-3850 3225);
PAINT GREEN (-3850 3225);
DISPLAY INVISIBLE (-3850 3225);
FORCEPROP 2 LAST CDS_LIB standard
J 0
(-3950 3300);
DISPLAY INVISIBLE (-3950 3300);
FORCEADD OFFPAGE..5
(-3950 3250);
FORCEPROP 2 LAST $XR0 43 
J 0
(-4204 3250);
DISPLAY 0.638298 (-4204 3250);
PAINT MONO (-4204 3250);
FORCEPROP 2 LAST PATH I53
J 0
(-4150 3300);
DISPLAY 1.021277 (-4150 3300);
DISPLAY INVISIBLE (-4150 3300);
FORCEPROP 2 LAST CDS_LIB standard
J 0
(-3950 3250);
PAINT MONO (-3950 3250);
DISPLAY INVISIBLE (-3950 3250);
FORCEPROP 1 LAST COMMENT_BODY TRUE
J 0
(-3850 3175);
DISPLAY 1.170213 (-3850 3175);
PAINT GREEN (-3850 3175);
DISPLAY INVISIBLE (-3850 3175);
FORCEPROP 1 LAST OFFPAGE TRUE
J 0
(-3625 3125);
DISPLAY 0.872340 (-3625 3125);
DISPLAY INVISIBLE (-3625 3125);
FORCEADD OFFPAGE..5
(-3950 3200);
FORCEPROP 2 LAST $XR0 43 
J 0
(-4204 3200);
DISPLAY 0.638298 (-4204 3200);
PAINT MONO (-4204 3200);
FORCEPROP 2 LAST PATH I54
J 0
(-4150 3250);
DISPLAY 1.021277 (-4150 3250);
DISPLAY INVISIBLE (-4150 3250);
FORCEPROP 2 LAST CDS_LIB standard
J 0
(-3950 3200);
DISPLAY INVISIBLE (-3950 3200);
FORCEPROP 1 LAST COMMENT_BODY TRUE
J 0
(-3850 3125);
DISPLAY 1.170213 (-3850 3125);
PAINT GREEN (-3850 3125);
DISPLAY INVISIBLE (-3850 3125);
FORCEPROP 1 LAST OFFPAGE TRUE
J 0
(-3625 3075);
DISPLAY 0.872340 (-3625 3075);
DISPLAY INVISIBLE (-3625 3075);
FORCEADD OFFPAGE..1
(-3950 3150);
FORCEPROP 2 LAST $XR0 190 
J 0
(-4232 3150);
DISPLAY 0.638298 (-4232 3150);
PAINT MONO (-4232 3150);
FORCEPROP 1 LAST COMMENT_BODY TRUE
J 0
(-3825 3050);
DISPLAY 1.170213 (-3825 3050);
PAINT GREEN (-3825 3050);
DISPLAY INVISIBLE (-3825 3050);
FORCEPROP 1 LAST OFFPAGE TRUE
J 0
(-3625 3025);
DISPLAY 0.872340 (-3625 3025);
DISPLAY INVISIBLE (-3625 3025);
FORCEPROP 2 LAST CDS_LIB standard
J 0
(-3950 3150);
DISPLAY INVISIBLE (-3950 3150);
FORCEPROP 2 LAST PATH I55
J 0
(-4200 3200);
DISPLAY 1.021277 (-4200 3200);
DISPLAY INVISIBLE (-4200 3200);
FORCEADD OFFPAGE..5
(-3950 3100);
FORCEPROP 2 LAST $XR1 299 
J 0
(-4355 3100);
DISPLAY 0.638298 (-4355 3100);
PAINT MONO (-4355 3100);
FORCEPROP 2 LAST $XR0 281 
J 0
(-4235 3100);
DISPLAY 0.638298 (-4235 3100);
PAINT MONO (-4235 3100);
FORCEPROP 2 LAST PATH I56
J 0
(-4200 3150);
DISPLAY 1.021277 (-4200 3150);
DISPLAY INVISIBLE (-4200 3150);
FORCEPROP 2 LAST CDS_LIB standard
J 0
(-3950 3100);
DISPLAY INVISIBLE (-3950 3100);
FORCEPROP 1 LAST COMMENT_BODY TRUE
J 0
(-3850 3025);
DISPLAY 1.170213 (-3850 3025);
PAINT GREEN (-3850 3025);
DISPLAY INVISIBLE (-3850 3025);
FORCEPROP 1 LAST OFFPAGE TRUE
J 0
(-3625 2975);
DISPLAY 0.872340 (-3625 2975);
DISPLAY INVISIBLE (-3625 2975);
FORCEADD OFFPAGE..1
(-3950 3050);
FORCEPROP 2 LAST $XR1 223 
J 0
(-4352 3050);
DISPLAY 0.638298 (-4352 3050);
PAINT MONO (-4352 3050);
FORCEPROP 2 LAST $XR0 216 
J 0
(-4232 3050);
DISPLAY 0.638298 (-4232 3050);
PAINT MONO (-4232 3050);
FORCEPROP 2 LAST PATH I57
J 0
(-4200 3100);
DISPLAY 1.021277 (-4200 3100);
DISPLAY INVISIBLE (-4200 3100);
FORCEPROP 2 LAST CDS_LIB standard
J 0
(-3950 3050);
PAINT MONO (-3950 3050);
DISPLAY INVISIBLE (-3950 3050);
FORCEPROP 1 LAST COMMENT_BODY TRUE
J 0
(-3825 2950);
DISPLAY 1.170213 (-3825 2950);
PAINT GREEN (-3825 2950);
DISPLAY INVISIBLE (-3825 2950);
FORCEPROP 1 LAST OFFPAGE TRUE
J 0
(-3625 2925);
DISPLAY 0.872340 (-3625 2925);
DISPLAY INVISIBLE (-3625 2925);
FORCEADD OFFPAGE..5
(-3950 2950);
FORCEPROP 2 LAST $XR0 222 
J 0
(-4235 2950);
DISPLAY 0.638298 (-4235 2950);
PAINT MONO (-4235 2950);
FORCEPROP 2 LAST PATH I58
J 0
(-4200 3000);
DISPLAY 1.021277 (-4200 3000);
DISPLAY INVISIBLE (-4200 3000);
FORCEPROP 1 LAST COMMENT_BODY TRUE
J 0
(-3850 2875);
DISPLAY 1.170213 (-3850 2875);
PAINT GREEN (-3850 2875);
DISPLAY INVISIBLE (-3850 2875);
FORCEPROP 1 LAST OFFPAGE TRUE
J 0
(-3625 2825);
DISPLAY 0.872340 (-3625 2825);
DISPLAY INVISIBLE (-3625 2825);
FORCEPROP 2 LAST CDS_LIB standard
J 0
(-3950 2950);
DISPLAY INVISIBLE (-3950 2950);
FORCEADD OFFPAGE..5
(-3950 3000);
FORCEPROP 2 LAST $XR7 245 
J 0
(-5075 3000);
DISPLAY 0.638298 (-5075 3000);
PAINT MONO (-5075 3000);
FORCEPROP 2 LAST $XR6 236 
J 0
(-4955 3000);
DISPLAY 0.638298 (-4955 3000);
PAINT MONO (-4955 3000);
FORCEPROP 2 LAST $XR5 233 
J 0
(-4835 3000);
DISPLAY 0.638298 (-4835 3000);
PAINT MONO (-4835 3000);
FORCEPROP 2 LAST $XR4 231 
J 0
(-4715 3000);
DISPLAY 0.638298 (-4715 3000);
PAINT MONO (-4715 3000);
FORCEPROP 2 LAST $XR3 227 
J 0
(-4595 3000);
DISPLAY 0.638298 (-4595 3000);
PAINT MONO (-4595 3000);
FORCEPROP 2 LAST $XR2 191 
J 0
(-4475 3000);
DISPLAY 0.638298 (-4475 3000);
PAINT MONO (-4475 3000);
FORCEPROP 2 LAST $XR1 161 
J 0
(-4355 3000);
DISPLAY 0.638298 (-4355 3000);
PAINT MONO (-4355 3000);
FORCEPROP 2 LAST $XR0 154 
J 0
(-4235 3000);
DISPLAY 0.638298 (-4235 3000);
PAINT MONO (-4235 3000);
FORCEPROP 2 LAST PATH I59
J 0
(-4200 3050);
DISPLAY 1.021277 (-4200 3050);
DISPLAY INVISIBLE (-4200 3050);
FORCEPROP 1 LAST COMMENT_BODY TRUE
J 0
(-3850 2925);
DISPLAY 1.170213 (-3850 2925);
PAINT GREEN (-3850 2925);
DISPLAY INVISIBLE (-3850 2925);
FORCEPROP 1 LAST OFFPAGE TRUE
J 0
(-3625 2875);
DISPLAY 0.872340 (-3625 2875);
DISPLAY INVISIBLE (-3625 2875);
FORCEPROP 2 LAST CDS_LIB standard
J 0
(-3950 3000);
DISPLAY INVISIBLE (-3950 3000);
FORCEADD OFFPAGE..1
R 2
(-100 3600);
FORCEPROP 2 LAST $XR0 266 
J 0
(86 3600);
DISPLAY 0.638298 (86 3600);
PAINT MONO (86 3600);
FORCEPROP 2 LAST PATH I6
J 0
(100 3650);
DISPLAY 1.021277 (100 3650);
DISPLAY INVISIBLE (100 3650);
FORCEPROP 1 LAST COMMENT_BODY TRUE
J 2
(-225 3500);
DISPLAY 1.170213 (-225 3500);
PAINT GREEN (-225 3500);
DISPLAY INVISIBLE (-225 3500);
FORCEPROP 1 LAST OFFPAGE TRUE
J 2
(-425 3475);
DISPLAY 1.170213 (-425 3475);
PAINT GREEN (-425 3475);
DISPLAY INVISIBLE (-425 3475);
FORCEPROP 2 LAST CDS_LIB standard
J 0
(-100 3600);
DISPLAY INVISIBLE (-100 3600);
FORCEADD OFFPAGE..5
(-3950 2900);
FORCEPROP 2 LAST $XR0 222 
J 0
(-4235 2900);
DISPLAY 0.638298 (-4235 2900);
PAINT MONO (-4235 2900);
FORCEPROP 2 LAST PATH I60
J 0
(-4200 2950);
DISPLAY 1.021277 (-4200 2950);
DISPLAY INVISIBLE (-4200 2950);
FORCEPROP 1 LAST COMMENT_BODY TRUE
J 0
(-3850 2825);
DISPLAY 1.170213 (-3850 2825);
PAINT GREEN (-3850 2825);
DISPLAY INVISIBLE (-3850 2825);
FORCEPROP 1 LAST OFFPAGE TRUE
J 0
(-3625 2775);
DISPLAY 0.872340 (-3625 2775);
DISPLAY INVISIBLE (-3625 2775);
FORCEPROP 2 LAST CDS_LIB standard
J 0
(-3950 2900);
PAINT MONO (-3950 2900);
DISPLAY INVISIBLE (-3950 2900);
FORCEADD OFFPAGE..1
(-3950 2850);
FORCEPROP 2 LAST $XR0 220 
J 0
(-4232 2850);
DISPLAY 0.638298 (-4232 2850);
PAINT MONO (-4232 2850);
FORCEPROP 2 LAST PATH I61
J 0
(-4200 2900);
DISPLAY 1.021277 (-4200 2900);
DISPLAY INVISIBLE (-4200 2900);
FORCEPROP 1 LAST OFFPAGE TRUE
J 0
(-3625 2725);
DISPLAY 0.872340 (-3625 2725);
DISPLAY INVISIBLE (-3625 2725);
FORCEPROP 1 LAST COMMENT_BODY TRUE
J 0
(-3825 2750);
DISPLAY 1.170213 (-3825 2750);
PAINT GREEN (-3825 2750);
DISPLAY INVISIBLE (-3825 2750);
FORCEPROP 2 LAST CDS_LIB standard
J 0
(-3950 2850);
DISPLAY INVISIBLE (-3950 2850);
FORCEADD OFFPAGE..1
(-3950 2750);
FORCEPROP 2 LAST $XR0 215 
J 0
(-4232 2750);
DISPLAY 0.638298 (-4232 2750);
PAINT MONO (-4232 2750);
FORCEPROP 2 LAST PATH I62
J 0
(-4200 2800);
DISPLAY 1.021277 (-4200 2800);
DISPLAY INVISIBLE (-4200 2800);
FORCEPROP 2 LAST CDS_LIB standard
J 0
(-3950 2750);
DISPLAY INVISIBLE (-3950 2750);
FORCEPROP 1 LAST COMMENT_BODY TRUE
J 0
(-3825 2650);
DISPLAY 1.170213 (-3825 2650);
PAINT GREEN (-3825 2650);
DISPLAY INVISIBLE (-3825 2650);
FORCEPROP 1 LAST OFFPAGE TRUE
J 0
(-3625 2625);
DISPLAY 0.872340 (-3625 2625);
DISPLAY INVISIBLE (-3625 2625);
FORCEADD OFFPAGE..5
(-3950 2800);
FORCEPROP 2 LAST $XR0 183 
J 0
(-4235 2800);
DISPLAY 0.638298 (-4235 2800);
PAINT MONO (-4235 2800);
FORCEPROP 2 LAST PATH I63
J 0
(-4200 2850);
DISPLAY 1.021277 (-4200 2850);
DISPLAY INVISIBLE (-4200 2850);
FORCEPROP 2 LAST CDS_LIB standard
J 0
(-3950 2800);
DISPLAY INVISIBLE (-3950 2800);
FORCEPROP 1 LAST COMMENT_BODY TRUE
J 0
(-3850 2725);
DISPLAY 1.170213 (-3850 2725);
PAINT GREEN (-3850 2725);
DISPLAY INVISIBLE (-3850 2725);
FORCEPROP 1 LAST OFFPAGE TRUE
J 0
(-3625 2675);
DISPLAY 0.872340 (-3625 2675);
DISPLAY INVISIBLE (-3625 2675);
FORCEADD OFFPAGE..1
(-3950 2700);
FORCEPROP 2 LAST $XR0 131 
J 0
(-4202 2700);
DISPLAY 0.638298 (-4202 2700);
PAINT MONO (-4202 2700);
FORCEPROP 2 LAST PATH I64
J 0
(-4200 2750);
DISPLAY 1.021277 (-4200 2750);
DISPLAY INVISIBLE (-4200 2750);
FORCEPROP 1 LAST OFFPAGE TRUE
J 0
(-3625 2575);
DISPLAY 0.872340 (-3625 2575);
DISPLAY INVISIBLE (-3625 2575);
FORCEPROP 1 LAST COMMENT_BODY TRUE
J 0
(-3825 2600);
DISPLAY 1.170213 (-3825 2600);
PAINT GREEN (-3825 2600);
DISPLAY INVISIBLE (-3825 2600);
FORCEPROP 2 LAST CDS_LIB standard
J 0
(-3950 2700);
PAINT MONO (-3950 2700);
DISPLAY INVISIBLE (-3950 2700);
FORCEADD OFFPAGE..1
(-3950 2650);
FORCEPROP 2 LAST $XR0 205 
J 0
(-4202 2650);
DISPLAY 0.638298 (-4202 2650);
PAINT MONO (-4202 2650);
FORCEPROP 2 LAST PATH I65
J 0
(-4200 2700);
DISPLAY 1.021277 (-4200 2700);
DISPLAY INVISIBLE (-4200 2700);
FORCEPROP 1 LAST OFFPAGE TRUE
J 0
(-3625 2525);
DISPLAY 0.872340 (-3625 2525);
DISPLAY INVISIBLE (-3625 2525);
FORCEPROP 1 LAST COMMENT_BODY TRUE
J 0
(-3825 2550);
DISPLAY 1.170213 (-3825 2550);
PAINT GREEN (-3825 2550);
DISPLAY INVISIBLE (-3825 2550);
FORCEPROP 2 LAST CDS_LIB standard
J 0
(-3950 2650);
PAINT MONO (-3950 2650);
DISPLAY INVISIBLE (-3950 2650);
FORCEADD OFFPAGE..1
(-3950 2550);
FORCEPROP 2 LAST $XR0 205 
J 0
(-4232 2550);
DISPLAY 0.638298 (-4232 2550);
PAINT MONO (-4232 2550);
FORCEPROP 2 LAST PATH I66
J 0
(-4200 2600);
DISPLAY 1.021277 (-4200 2600);
DISPLAY INVISIBLE (-4200 2600);
FORCEPROP 1 LAST COMMENT_BODY TRUE
J 0
(-3825 2450);
DISPLAY 1.170213 (-3825 2450);
PAINT GREEN (-3825 2450);
DISPLAY INVISIBLE (-3825 2450);
FORCEPROP 1 LAST OFFPAGE TRUE
J 0
(-3625 2425);
DISPLAY 0.872340 (-3625 2425);
DISPLAY INVISIBLE (-3625 2425);
FORCEPROP 2 LAST CDS_LIB standard
J 0
(-3950 2550);
DISPLAY INVISIBLE (-3950 2550);
FORCEADD OFFPAGE..5
(-3950 2600);
FORCEPROP 2 LAST $XR0 182 
J 0
(-4235 2600);
DISPLAY 0.638298 (-4235 2600);
PAINT MONO (-4235 2600);
FORCEPROP 2 LAST PATH I67
J 0
(-4200 2650);
DISPLAY 1.021277 (-4200 2650);
DISPLAY INVISIBLE (-4200 2650);
FORCEPROP 2 LAST CDS_LIB standard
J 0
(-3950 2600);
DISPLAY INVISIBLE (-3950 2600);
FORCEPROP 1 LAST OFFPAGE TRUE
J 0
(-3625 2475);
DISPLAY 0.872340 (-3625 2475);
DISPLAY INVISIBLE (-3625 2475);
FORCEPROP 1 LAST COMMENT_BODY TRUE
J 0
(-3850 2525);
DISPLAY 1.170213 (-3850 2525);
PAINT GREEN (-3850 2525);
DISPLAY INVISIBLE (-3850 2525);
FORCEADD OFFPAGE..1
(-3950 2500);
FORCEPROP 2 LAST $XR0 220 
J 0
(-4202 2500);
DISPLAY 0.638298 (-4202 2500);
PAINT MONO (-4202 2500);
FORCEPROP 2 LAST PATH I68
J 0
(-4200 2550);
DISPLAY 1.021277 (-4200 2550);
DISPLAY INVISIBLE (-4200 2550);
FORCEPROP 1 LAST OFFPAGE TRUE
J 0
(-3625 2375);
DISPLAY 0.872340 (-3625 2375);
DISPLAY INVISIBLE (-3625 2375);
FORCEPROP 1 LAST COMMENT_BODY TRUE
J 0
(-3825 2400);
DISPLAY 1.170213 (-3825 2400);
PAINT GREEN (-3825 2400);
DISPLAY INVISIBLE (-3825 2400);
FORCEPROP 2 LAST CDS_LIB standard
J 0
(-3950 2500);
DISPLAY INVISIBLE (-3950 2500);
FORCEADD OFFPAGE..5
(-3950 2450);
FORCEPROP 2 LAST $XR1 220 
J 0
(-4355 2450);
DISPLAY 0.638298 (-4355 2450);
PAINT MONO (-4355 2450);
FORCEPROP 2 LAST $XR0 218 
J 0
(-4235 2450);
DISPLAY 0.638298 (-4235 2450);
PAINT MONO (-4235 2450);
FORCEPROP 2 LAST PATH I69
J 0
(-4200 2500);
DISPLAY 1.021277 (-4200 2500);
DISPLAY INVISIBLE (-4200 2500);
FORCEPROP 2 LAST CDS_LIB standard
J 0
(-3950 2450);
DISPLAY INVISIBLE (-3950 2450);
FORCEPROP 1 LAST OFFPAGE TRUE
J 0
(-3625 2325);
DISPLAY 0.872340 (-3625 2325);
DISPLAY INVISIBLE (-3625 2325);
FORCEPROP 1 LAST COMMENT_BODY TRUE
J 0
(-3850 2375);
DISPLAY 1.170213 (-3850 2375);
PAINT GREEN (-3850 2375);
DISPLAY INVISIBLE (-3850 2375);
FORCEADD OFFPAGE..2
(-100 3650);
FORCEPROP 2 LAST $XR0 222 
J 0
(89 3650);
DISPLAY 0.638298 (89 3650);
PAINT MONO (89 3650);
FORCEPROP 2 LAST PATH I7
J 0
(100 3700);
DISPLAY 1.021277 (100 3700);
DISPLAY INVISIBLE (100 3700);
FORCEPROP 2 LAST CDS_LIB standard
J 0
(-100 3650);
DISPLAY INVISIBLE (-100 3650);
FORCEPROP 1 LAST COMMENT_BODY TRUE
J 0
(-145 3555);
DISPLAY 1.170213 (-145 3555);
PAINT GREEN (-145 3555);
DISPLAY INVISIBLE (-145 3555);
FORCEPROP 1 LAST OFFPAGE TRUE
J 0
(225 3525);
DISPLAY 1.170213 (225 3525);
PAINT GREEN (225 3525);
DISPLAY INVISIBLE (225 3525);
FORCEADD OFFPAGE..1
(-3950 2400);
FORCEPROP 2 LAST $XR0 203 
J 0
(-4232 2400);
DISPLAY 0.638298 (-4232 2400);
PAINT MONO (-4232 2400);
FORCEPROP 2 LAST PATH I70
J 0
(-4200 2450);
DISPLAY 1.021277 (-4200 2450);
DISPLAY INVISIBLE (-4200 2450);
FORCEPROP 1 LAST OFFPAGE TRUE
J 0
(-3625 2275);
DISPLAY 0.872340 (-3625 2275);
DISPLAY INVISIBLE (-3625 2275);
FORCEPROP 1 LAST COMMENT_BODY TRUE
J 0
(-3825 2300);
DISPLAY 1.170213 (-3825 2300);
PAINT GREEN (-3825 2300);
DISPLAY INVISIBLE (-3825 2300);
FORCEPROP 2 LAST CDS_LIB standard
J 0
(-3950 2400);
PAINT MONO (-3950 2400);
DISPLAY INVISIBLE (-3950 2400);
FORCEADD OFFPAGE..1
(-3950 2350);
FORCEPROP 2 LAST $XR1 204 
J 0
(-4322 2350);
DISPLAY 0.638298 (-4322 2350);
PAINT MONO (-4322 2350);
FORCEPROP 2 LAST $XR0 184 
J 0
(-4202 2350);
DISPLAY 0.638298 (-4202 2350);
PAINT MONO (-4202 2350);
FORCEPROP 2 LAST PATH I71
J 0
(-4200 2400);
DISPLAY 1.021277 (-4200 2400);
DISPLAY INVISIBLE (-4200 2400);
FORCEPROP 1 LAST COMMENT_BODY TRUE
J 0
(-3825 2250);
DISPLAY 1.170213 (-3825 2250);
PAINT GREEN (-3825 2250);
DISPLAY INVISIBLE (-3825 2250);
FORCEPROP 1 LAST OFFPAGE TRUE
J 0
(-3625 2225);
DISPLAY 0.872340 (-3625 2225);
DISPLAY INVISIBLE (-3625 2225);
FORCEPROP 2 LAST CDS_LIB standard
J 0
(-3950 2350);
PAINT MONO (-3950 2350);
DISPLAY INVISIBLE (-3950 2350);
FORCEADD OFFPAGE..5
(-3950 2300);
FORCEPROP 2 LAST $XR0 183 
J 0
(-4235 2300);
DISPLAY 0.638298 (-4235 2300);
PAINT MONO (-4235 2300);
FORCEPROP 2 LAST PATH I72
J 0
(-4200 2350);
DISPLAY 1.021277 (-4200 2350);
DISPLAY INVISIBLE (-4200 2350);
FORCEPROP 1 LAST COMMENT_BODY TRUE
J 0
(-3850 2225);
DISPLAY 1.170213 (-3850 2225);
PAINT GREEN (-3850 2225);
DISPLAY INVISIBLE (-3850 2225);
FORCEPROP 1 LAST OFFPAGE TRUE
J 0
(-3625 2175);
DISPLAY 0.872340 (-3625 2175);
DISPLAY INVISIBLE (-3625 2175);
FORCEPROP 2 LAST CDS_LIB standard
J 0
(-3950 2300);
PAINT MONO (-3950 2300);
DISPLAY INVISIBLE (-3950 2300);
FORCEADD OFFPAGE..1
(-3950 2250);
FORCEPROP 2 LAST $XR0 239 
J 0
(-4232 2250);
DISPLAY 0.638298 (-4232 2250);
PAINT MONO (-4232 2250);
FORCEPROP 2 LAST PATH I73
J 0
(-4200 2300);
DISPLAY 1.021277 (-4200 2300);
DISPLAY INVISIBLE (-4200 2300);
FORCEPROP 2 LAST CDS_LIB standard
J 0
(-3950 2250);
DISPLAY INVISIBLE (-3950 2250);
FORCEPROP 1 LAST OFFPAGE TRUE
J 0
(-3625 2125);
DISPLAY 0.872340 (-3625 2125);
DISPLAY INVISIBLE (-3625 2125);
FORCEPROP 1 LAST COMMENT_BODY TRUE
J 0
(-3825 2150);
DISPLAY 1.170213 (-3825 2150);
PAINT GREEN (-3825 2150);
DISPLAY INVISIBLE (-3825 2150);
FORCEADD OFFPAGE..5
(-3950 2200);
FORCEPROP 2 LAST $XR0 215 
J 0
(-4235 2200);
DISPLAY 0.638298 (-4235 2200);
PAINT MONO (-4235 2200);
FORCEPROP 2 LAST PATH I74
J 0
(-4200 2250);
DISPLAY 1.021277 (-4200 2250);
DISPLAY INVISIBLE (-4200 2250);
FORCEPROP 2 LAST CDS_LIB standard
J 0
(-3950 2200);
DISPLAY INVISIBLE (-3950 2200);
FORCEPROP 1 LAST OFFPAGE TRUE
J 0
(-3625 2075);
DISPLAY 0.872340 (-3625 2075);
DISPLAY INVISIBLE (-3625 2075);
FORCEPROP 1 LAST COMMENT_BODY TRUE
J 0
(-3850 2125);
DISPLAY 1.170213 (-3850 2125);
PAINT GREEN (-3850 2125);
DISPLAY INVISIBLE (-3850 2125);
FORCEADD OFFPAGE..5
(-3950 2150);
FORCEPROP 2 LAST $XR1 220 
J 0
(-4355 2150);
DISPLAY 0.638298 (-4355 2150);
PAINT MONO (-4355 2150);
FORCEPROP 2 LAST $XR0 218 
J 0
(-4235 2150);
DISPLAY 0.638298 (-4235 2150);
PAINT MONO (-4235 2150);
FORCEPROP 2 LAST PATH I75
J 0
(-4200 2200);
DISPLAY 1.021277 (-4200 2200);
DISPLAY INVISIBLE (-4200 2200);
FORCEPROP 2 LAST CDS_LIB standard
J 0
(-3950 2150);
DISPLAY INVISIBLE (-3950 2150);
FORCEPROP 1 LAST OFFPAGE TRUE
J 0
(-3625 2025);
DISPLAY 0.872340 (-3625 2025);
DISPLAY INVISIBLE (-3625 2025);
FORCEPROP 1 LAST COMMENT_BODY TRUE
J 0
(-3850 2075);
DISPLAY 1.170213 (-3850 2075);
PAINT GREEN (-3850 2075);
DISPLAY INVISIBLE (-3850 2075);
FORCEADD OFFPAGE..1
(-3950 2100);
FORCEPROP 2 LAST $XR0 215 
J 0
(-4232 2100);
DISPLAY 0.638298 (-4232 2100);
PAINT MONO (-4232 2100);
FORCEPROP 2 LAST CDS_LIB standard
J 0
(-3950 2100);
PAINT MONO (-3950 2100);
DISPLAY INVISIBLE (-3950 2100);
FORCEPROP 2 LAST PATH I76
J 0
(-4200 2150);
DISPLAY 1.021277 (-4200 2150);
DISPLAY INVISIBLE (-4200 2150);
FORCEPROP 1 LAST COMMENT_BODY TRUE
J 0
(-3825 2000);
DISPLAY 1.170213 (-3825 2000);
PAINT GREEN (-3825 2000);
DISPLAY INVISIBLE (-3825 2000);
FORCEPROP 1 LAST OFFPAGE TRUE
J 0
(-3625 1975);
DISPLAY 0.872340 (-3625 1975);
DISPLAY INVISIBLE (-3625 1975);
FORCEADD OFFPAGE..1
(-3950 2050);
FORCEPROP 2 LAST $XR1 183 
J 0
(-4322 2050);
DISPLAY 0.638298 (-4322 2050);
PAINT MONO (-4322 2050);
FORCEPROP 2 LAST $XR0 191 
J 0
(-4202 2050);
DISPLAY 0.638298 (-4202 2050);
PAINT MONO (-4202 2050);
FORCEPROP 2 LAST CDS_LIB standard
J 0
(-3950 2050);
DISPLAY INVISIBLE (-3950 2050);
FORCEPROP 2 LAST PATH I77
J 0
(-4200 2100);
DISPLAY 1.021277 (-4200 2100);
DISPLAY INVISIBLE (-4200 2100);
FORCEPROP 1 LAST OFFPAGE TRUE
J 0
(-3625 1925);
DISPLAY 0.872340 (-3625 1925);
DISPLAY INVISIBLE (-3625 1925);
FORCEPROP 1 LAST COMMENT_BODY TRUE
J 0
(-3825 1950);
DISPLAY 1.170213 (-3825 1950);
PAINT GREEN (-3825 1950);
DISPLAY INVISIBLE (-3825 1950);
FORCEADD OFFPAGE..1
(-3950 2000);
FORCEPROP 2 LAST $XR0 215 
J 0
(-4202 2000);
DISPLAY 0.638298 (-4202 2000);
PAINT MONO (-4202 2000);
FORCEPROP 2 LAST CDS_LIB standard
J 0
(-3950 2000);
DISPLAY INVISIBLE (-3950 2000);
FORCEPROP 2 LAST PATH I78
J 0
(-4200 2050);
DISPLAY 1.021277 (-4200 2050);
DISPLAY INVISIBLE (-4200 2050);
FORCEPROP 1 LAST OFFPAGE TRUE
J 0
(-3625 1875);
DISPLAY 0.872340 (-3625 1875);
DISPLAY INVISIBLE (-3625 1875);
FORCEPROP 1 LAST COMMENT_BODY TRUE
J 0
(-3825 1900);
DISPLAY 1.170213 (-3825 1900);
PAINT GREEN (-3825 1900);
DISPLAY INVISIBLE (-3825 1900);
FORCEADD OFFPAGE..1
(-5775 875);
FORCEPROP 2 LAST $XR1 306 
J 0
(-6147 875);
DISPLAY 0.638298 (-6147 875);
PAINT MONO (-6147 875);
FORCEPROP 2 LAST $XR0 301 
J 0
(-6027 875);
DISPLAY 0.638298 (-6027 875);
PAINT MONO (-6027 875);
FORCEPROP 2 LAST PATH I79
J 0
(-6025 925);
DISPLAY 1.021277 (-6025 925);
DISPLAY INVISIBLE (-6025 925);
FORCEPROP 2 LAST CDS_LIB standard
J 0
(-5775 875);
DISPLAY INVISIBLE (-5775 875);
FORCEPROP 1 LAST OFFPAGE TRUE
J 0
(-5450 750);
DISPLAY 0.872340 (-5450 750);
DISPLAY INVISIBLE (-5450 750);
FORCEPROP 1 LAST COMMENT_BODY TRUE
J 0
(-5650 775);
DISPLAY 1.170213 (-5650 775);
PAINT GREEN (-5650 775);
DISPLAY INVISIBLE (-5650 775);
FORCEADD OFFPAGE..1
R 2
(-100 3550);
FORCEPROP 2 LAST $XR0 205 
J 0
(86 3550);
DISPLAY 0.638298 (86 3550);
PAINT MONO (86 3550);
FORCEPROP 2 LAST PATH I8
J 0
(100 3600);
DISPLAY 1.021277 (100 3600);
DISPLAY INVISIBLE (100 3600);
FORCEPROP 2 LAST CDS_LIB standard
J 0
(-100 3550);
DISPLAY INVISIBLE (-100 3550);
FORCEPROP 1 LAST OFFPAGE TRUE
J 2
(-425 3425);
DISPLAY 1.170213 (-425 3425);
PAINT GREEN (-425 3425);
DISPLAY INVISIBLE (-425 3425);
FORCEPROP 1 LAST COMMENT_BODY TRUE
J 2
(-225 3450);
DISPLAY 1.170213 (-225 3450);
PAINT GREEN (-225 3450);
DISPLAY INVISIBLE (-225 3450);
FORCEADD Q_RES..1
(-4550 875);
FORCEPROP 1 LAST PART_NUMBER CS00002JB13
J 0
(-4600 925);
DISPLAY 0.404255 (-4600 925);
DISPLAY INVISIBLE (-4600 925);
FORCEPROP 1 LAST MATERIAL CHIP
J 0
(-4300 875);
DISPLAY 0.510638 (-4300 875);
FORCEPROP 1 LAST TOLERANCE 5%
J 0
(-4375 875);
DISPLAY 0.510638 (-4375 875);
FORCEPROP 1 LAST VALUE 0
J 2
(-4400 875);
DISPLAY 0.510638 (-4400 875);
FORCEPROP 1 LAST $LOCATION R4056
J 0
(-4750 875);
DISPLAY 0.510638 (-4750 875);
FORCEPROP 1 LASTPIN (-4650 875) $PN 1
J 0
(-4638 887);
DISPLAY 0.787234 (-4638 887);
FORCEPROP 1 LASTPIN (-4450 875) $PN 2
J 0
(-4488 887);
DISPLAY 0.787234 (-4488 887);
FORCEPROP 1 LAST PATH I80
J 0
(-4600 1025);
DISPLAY 0.978723 (-4600 1025);
PAINT WHITE (-4600 1025);
DISPLAY INVISIBLE (-4600 1025);
FORCEPROP 2 LAST CDS_LIB pure_quanta
J 0
(-4550 875);
PAINT MONO (-4550 875);
DISPLAY INVISIBLE (-4550 875);
FORCEPROP 1 LAST WATTAGE 1/16W
J 2
(-4375 950);
DISPLAY 0.404255 (-4375 950);
DISPLAY INVISIBLE (-4375 950);
FORCEPROP 1 LAST PACK_TYPE 0402LF
J 0
(-4300 875);
DISPLAY 0.510638 (-4300 875);
DISPLAY INVISIBLE (-4300 875);
FORCEPROP 2 LAST CDS_LOCATION R4056
J 0
(-4600 1075);
DISPLAY 1.021277 (-4600 1075);
DISPLAY INVISIBLE (-4600 1075);
FORCEPROP 2 LAST $SEC 1
J 0
(-4600 1075);
DISPLAY 0.680851 (-4600 1075);
PAINT MONO (-4600 1075);
DISPLAY INVISIBLE (-4600 1075);
FORCEPROP 2 LAST CDS_SEC 1
J 0
(-4600 1075);
DISPLAY 1.021277 (-4600 1075);
DISPLAY INVISIBLE (-4600 1075);
FORCEADD OFFPAGE..2
(-3200 875);
FORCEPROP 2 LAST $XR0 215 
J 0
(-3011 875);
DISPLAY 0.638298 (-3011 875);
PAINT MONO (-3011 875);
FORCEPROP 2 LAST PATH I81
J 0
(-3000 925);
DISPLAY 1.021277 (-3000 925);
DISPLAY INVISIBLE (-3000 925);
FORCEPROP 1 LAST COMMENT_BODY TRUE
J 0
(-3245 780);
DISPLAY 0.872340 (-3245 780);
PAINT PEACH (-3245 780);
DISPLAY INVISIBLE (-3245 780);
FORCEPROP 1 LAST OFFPAGE TRUE
J 0
(-2875 750);
DISPLAY 0.872340 (-2875 750);
PAINT GREEN (-2875 750);
DISPLAY INVISIBLE (-2875 750);
FORCEPROP 2 LAST CDS_LIB standard
J 0
(-3200 875);
PAINT MONO (-3200 875);
DISPLAY INVISIBLE (-3200 875);
FORCEADD OFFPAGE..2
(-3200 700);
FORCEPROP 2 LAST $XR0 215 
J 0
(-3011 700);
DISPLAY 0.638298 (-3011 700);
PAINT MONO (-3011 700);
FORCEPROP 2 LAST PATH I82
J 0
(-3000 750);
DISPLAY 1.021277 (-3000 750);
DISPLAY INVISIBLE (-3000 750);
FORCEPROP 1 LAST COMMENT_BODY TRUE
J 0
(-3245 605);
DISPLAY 0.872340 (-3245 605);
PAINT PEACH (-3245 605);
DISPLAY INVISIBLE (-3245 605);
FORCEPROP 1 LAST OFFPAGE TRUE
J 0
(-2875 575);
DISPLAY 0.872340 (-2875 575);
PAINT GREEN (-2875 575);
DISPLAY INVISIBLE (-2875 575);
FORCEPROP 2 LAST CDS_LIB standard
J 0
(-3200 700);
PAINT MONO (-3200 700);
DISPLAY INVISIBLE (-3200 700);
FORCEADD OFFPAGE..1
(-5775 700);
FORCEPROP 2 LAST $XR1 227 
J 0
(-6147 700);
DISPLAY 0.638298 (-6147 700);
PAINT MONO (-6147 700);
FORCEPROP 2 LAST $XR0 144 
J 0
(-6027 700);
DISPLAY 0.638298 (-6027 700);
PAINT MONO (-6027 700);
FORCEPROP 1 LAST COMMENT_BODY TRUE
J 0
(-5650 600);
DISPLAY 1.170213 (-5650 600);
PAINT GREEN (-5650 600);
DISPLAY INVISIBLE (-5650 600);
FORCEPROP 1 LAST OFFPAGE TRUE
J 0
(-5450 575);
DISPLAY 0.872340 (-5450 575);
DISPLAY INVISIBLE (-5450 575);
FORCEPROP 2 LAST PATH I84
J 0
(-6025 750);
DISPLAY 1.021277 (-6025 750);
DISPLAY INVISIBLE (-6025 750);
FORCEPROP 2 LAST CDS_LIB standard
J 0
(-5775 700);
DISPLAY INVISIBLE (-5775 700);
FORCEADD OFFPAGE..1
(-3950 1950);
FORCEPROP 2 LAST $XR0 215 
J 0
(-4202 1950);
DISPLAY 0.638298 (-4202 1950);
PAINT MONO (-4202 1950);
FORCEPROP 1 LAST COMMENT_BODY TRUE
J 0
(-3825 1850);
DISPLAY 1.170213 (-3825 1850);
PAINT GREEN (-3825 1850);
DISPLAY INVISIBLE (-3825 1850);
FORCEPROP 1 LAST OFFPAGE TRUE
J 0
(-3625 1825);
DISPLAY 0.872340 (-3625 1825);
DISPLAY INVISIBLE (-3625 1825);
FORCEPROP 2 LAST PATH I85
J 0
(-3900 2025);
DISPLAY 1.021277 (-3900 2025);
DISPLAY INVISIBLE (-3900 2025);
FORCEPROP 2 LAST CDS_LIB standard
J 0
(-3950 1950);
DISPLAY INVISIBLE (-3950 1950);
FORCEADD Q_RES..2
(1775 1825);
FORCEPROP 1 LAST PART_NUMBER CS31002FB08
J 0
(1815 1700);
DISPLAY 0.638298 (1815 1700);
DISPLAY INVISIBLE (1815 1700);
FORCEPROP 1 LAST VALUE 10K
J 0
(1820 1900);
DISPLAY 0.638298 (1820 1900);
FORCEPROP 1 LAST PACK_TYPE 0402LF
J 0
(1815 1650);
DISPLAY 0.638298 (1815 1650);
FORCEPROP 1 LAST MATERIAL CHIP
J 0
(1815 1750);
DISPLAY 0.638298 (1815 1750);
FORCEPROP 1 LAST TOLERANCE 1%
J 0
(1820 1850);
DISPLAY 0.638298 (1820 1850);
FORCEPROP 1 LAST WATTAGE 1/16W
J 0
(1815 1800);
DISPLAY 0.638298 (1815 1800);
FORCEPROP 1 LAST $LOCATION R4086
J 0
(1820 1950);
DISPLAY 0.978723 (1820 1950);
FORCEPROP 1 LASTPIN (1775 1925) $PN 1
J 0
(1780 1887);
DISPLAY 0.787234 (1780 1887);
PAINT MONO (1780 1887);
FORCEPROP 1 LASTPIN (1775 1725) $PN 2
J 0
(1780 1735);
DISPLAY 0.787234 (1780 1735);
PAINT MONO (1780 1735);
FORCEPROP 2 LAST CDS_LIB pure_quanta
J 0
(1775 1825);
DISPLAY INVISIBLE (1775 1825);
FORCEPROP 1 LAST PATH I86
J 0
(1825 2000);
DISPLAY 0.978723 (1825 2000);
PAINT WHITE (1825 2000);
DISPLAY INVISIBLE (1825 2000);
FORCEPROP 0 LAST CDS_LOCATION R4086
J 0
(1825 2000);
DISPLAY 1.021277 (1825 2000);
DISPLAY INVISIBLE (1825 2000);
FORCEPROP 0 LAST $SEC 1
J 0
(1825 2000);
DISPLAY 0.680851 (1825 2000);
PAINT MONO (1825 2000);
DISPLAY INVISIBLE (1825 2000);
FORCEPROP 0 LAST CDS_SEC 1
J 0
(1825 2000);
DISPLAY 1.021277 (1825 2000);
DISPLAY INVISIBLE (1825 2000);
FORCEADD UNIVERSAL_POWER..1
(1775 2050);
FORCEPROP 3 LASTPIN (1775 2000) SIG_NAME P3V3_AUX_FPGA_VCCIO2\g
J 0
(1785 2010);
DISPLAY 0.659574 (1785 2010);
PAINT MONO (1785 2010);
DISPLAY INVISIBLE (1785 2010);
FORCEPROP 1 LAST HDL_POWER P3V3_AUX_FPGA_VCCIO2
J 1
(1775 2100);
DISPLAY 0.872340 (1775 2100);
PAINT GREEN (1775 2100);
FORCEPROP 2 LAST CDS_LIB logical_power
J 0
(1775 2050);
DISPLAY INVISIBLE (1775 2050);
FORCEPROP 1 LAST PATH I87
J 0
(1825 2075);
DISPLAY 0.872340 (1825 2075);
PAINT AQUA (1825 2075);
DISPLAY INVISIBLE (1825 2075);
FORCEADD OFFPAGE..1
(-3950 1800);
FORCEPROP 2 LAST $XR0 214 
J 0
(-4202 1800);
DISPLAY 0.638298 (-4202 1800);
PAINT MONO (-4202 1800);
FORCEPROP 1 LAST OFFPAGE TRUE
J 0
(-3625 1675);
DISPLAY 0.872340 (-3625 1675);
DISPLAY INVISIBLE (-3625 1675);
FORCEPROP 1 LAST COMMENT_BODY TRUE
J 0
(-3825 1700);
DISPLAY 1.170213 (-3825 1700);
PAINT GREEN (-3825 1700);
DISPLAY INVISIBLE (-3825 1700);
FORCEPROP 2 LAST CDS_LIB standard
J 0
(-3950 1800);
DISPLAY INVISIBLE (-3950 1800);
FORCEPROP 2 LAST PATH I88
J 0
(-4200 1850);
DISPLAY 1.021277 (-4200 1850);
DISPLAY INVISIBLE (-4200 1850);
FORCEADD Q_RES..1
(-4550 525);
FORCEPROP 1 LAST PART_NUMBER CS03322FB03
J 0
(-4700 600);
DISPLAY 0.638298 (-4700 600);
DISPLAY INVISIBLE (-4700 600);
FORCEPROP 1 LAST TOLERANCE 1%
J 0
(-4275 525);
DISPLAY 0.638298 (-4275 525);
FORCEPROP 1 LAST VALUE 33.2
J 2
(-4300 525);
DISPLAY 0.638298 (-4300 525);
FORCEPROP 1 LAST MATERIAL CHIP
J 0
(-4200 525);
DISPLAY 0.638298 (-4200 525);
FORCEPROP 1 LAST $LOCATION R4143
J 0
(-4825 525);
DISPLAY 0.787234 (-4825 525);
FORCEPROP 1 LASTPIN (-4650 525) $PN 1
J 0
(-4638 537);
DISPLAY 0.787234 (-4638 537);
FORCEPROP 1 LASTPIN (-4450 525) $PN 2
J 0
(-4488 537);
DISPLAY 0.787234 (-4488 537);
FORCEPROP 2 LAST CDS_LIB pure_quanta
J 0
(-4550 525);
PAINT MONO (-4550 525);
DISPLAY INVISIBLE (-4550 525);
FORCEPROP 1 LAST PATH I89
J 0
(-4600 675);
DISPLAY 0.978723 (-4600 675);
PAINT WHITE (-4600 675);
DISPLAY INVISIBLE (-4600 675);
FORCEPROP 1 LAST WATTAGE 1/16W
J 2
(-4350 650);
DISPLAY 0.638298 (-4350 650);
DISPLAY INVISIBLE (-4350 650);
FORCEPROP 1 LAST PACK_TYPE 0402LF
J 0
(-4700 650);
DISPLAY 0.638298 (-4700 650);
DISPLAY INVISIBLE (-4700 650);
FORCEPROP 2 LAST CDS_LOCATION R4143
J 0
(-4600 725);
DISPLAY 1.021277 (-4600 725);
DISPLAY INVISIBLE (-4600 725);
FORCEPROP 2 LAST $SEC 1
J 0
(-4600 725);
DISPLAY 0.680851 (-4600 725);
PAINT MONO (-4600 725);
DISPLAY INVISIBLE (-4600 725);
FORCEPROP 2 LAST CDS_SEC 1
J 0
(-4600 725);
DISPLAY 1.021277 (-4600 725);
DISPLAY INVISIBLE (-4600 725);
FORCEADD OFFPAGE..2
(-75 3450);
FORCEPROP 2 LAST $XR1 184 
J 0
(234 3450);
DISPLAY 0.638298 (234 3450);
PAINT MONO (234 3450);
FORCEPROP 2 LAST $XR0 204 
J 0
(114 3450);
DISPLAY 0.638298 (114 3450);
PAINT MONO (114 3450);
FORCEPROP 2 LAST PATH I9
J 0
(250 3500);
DISPLAY 1.021277 (250 3500);
DISPLAY INVISIBLE (250 3500);
FORCEPROP 2 LAST CDS_LIB standard
J 0
(-75 3450);
DISPLAY INVISIBLE (-75 3450);
FORCEPROP 1 LAST COMMENT_BODY TRUE
J 0
(-120 3355);
DISPLAY 1.170213 (-120 3355);
PAINT GREEN (-120 3355);
DISPLAY INVISIBLE (-120 3355);
FORCEPROP 1 LAST OFFPAGE TRUE
J 0
(250 3325);
DISPLAY 1.170213 (250 3325);
PAINT GREEN (250 3325);
DISPLAY INVISIBLE (250 3325);
FORCEADD OFFPAGE..1
(-5775 525);
FORCEPROP 2 LAST $XR0 146 
J 0
(-6027 525);
DISPLAY 0.638298 (-6027 525);
PAINT MONO (-6027 525);
FORCEPROP 2 LAST CDS_LIB standard
J 0
(-5775 525);
DISPLAY INVISIBLE (-5775 525);
FORCEPROP 2 LAST PATH I90
J 0
(-5725 600);
DISPLAY 1.021277 (-5725 600);
DISPLAY INVISIBLE (-5725 600);
FORCEPROP 1 LAST COMMENT_BODY TRUE
J 0
(-5650 425);
DISPLAY 1.170213 (-5650 425);
PAINT GREEN (-5650 425);
DISPLAY INVISIBLE (-5650 425);
FORCEPROP 1 LAST OFFPAGE TRUE
J 0
(-5450 400);
DISPLAY 0.872340 (-5450 400);
DISPLAY INVISIBLE (-5450 400);
FORCEADD OFFPAGE..2
(-3175 525);
FORCEPROP 2 LAST $XR0 215 
J 0
(-2986 525);
DISPLAY 0.638298 (-2986 525);
PAINT MONO (-2986 525);
FORCEPROP 2 LAST CDS_LIB standard
J 0
(-3175 525);
DISPLAY INVISIBLE (-3175 525);
FORCEPROP 2 LAST PATH I91
J 0
(-3000 600);
DISPLAY 1.021277 (-3000 600);
DISPLAY INVISIBLE (-3000 600);
FORCEPROP 1 LAST COMMENT_BODY TRUE
J 0
(-3220 430);
DISPLAY 0.872340 (-3220 430);
PAINT PEACH (-3220 430);
DISPLAY INVISIBLE (-3220 430);
FORCEPROP 1 LAST OFFPAGE TRUE
J 0
(-2850 400);
DISPLAY 0.872340 (-2850 400);
PAINT GREEN (-2850 400);
DISPLAY INVISIBLE (-2850 400);
FORCEADD OFFPAGE..2
(-3175 350);
FORCEPROP 2 LAST $XR0 215 
J 0
(-2986 350);
DISPLAY 0.638298 (-2986 350);
PAINT MONO (-2986 350);
FORCEPROP 2 LAST PATH I92
J 0
(-3000 425);
DISPLAY 1.021277 (-3000 425);
DISPLAY INVISIBLE (-3000 425);
FORCEPROP 2 LAST CDS_LIB standard
J 0
(-3175 350);
DISPLAY INVISIBLE (-3175 350);
FORCEPROP 1 LAST COMMENT_BODY TRUE
J 0
(-3220 255);
DISPLAY 0.872340 (-3220 255);
PAINT PEACH (-3220 255);
DISPLAY INVISIBLE (-3220 255);
FORCEPROP 1 LAST OFFPAGE TRUE
J 0
(-2850 225);
DISPLAY 0.872340 (-2850 225);
PAINT GREEN (-2850 225);
DISPLAY INVISIBLE (-2850 225);
FORCEADD Q_RES..1
(-4550 350);
FORCEPROP 1 LAST PART_NUMBER CS03322FB03
J 0
(-4700 425);
DISPLAY 0.638298 (-4700 425);
DISPLAY INVISIBLE (-4700 425);
FORCEPROP 1 LAST TOLERANCE 1%
J 0
(-4275 350);
DISPLAY 0.638298 (-4275 350);
FORCEPROP 1 LAST VALUE 33.2
J 2
(-4300 350);
DISPLAY 0.638298 (-4300 350);
FORCEPROP 1 LAST MATERIAL CHIP
J 0
(-4200 350);
DISPLAY 0.638298 (-4200 350);
FORCEPROP 1 LAST $LOCATION R4144
J 0
(-4825 350);
DISPLAY 0.787234 (-4825 350);
FORCEPROP 1 LASTPIN (-4650 350) $PN 1
J 0
(-4638 362);
DISPLAY 0.787234 (-4638 362);
FORCEPROP 1 LASTPIN (-4450 350) $PN 2
J 0
(-4488 362);
DISPLAY 0.787234 (-4488 362);
FORCEPROP 2 LAST CDS_LIB pure_quanta
J 0
(-4550 350);
PAINT MONO (-4550 350);
DISPLAY INVISIBLE (-4550 350);
FORCEPROP 1 LAST PACK_TYPE 0402LF
J 0
(-4700 475);
DISPLAY 0.638298 (-4700 475);
DISPLAY INVISIBLE (-4700 475);
FORCEPROP 1 LAST WATTAGE 1/16W
J 2
(-4350 475);
DISPLAY 0.638298 (-4350 475);
DISPLAY INVISIBLE (-4350 475);
FORCEPROP 1 LAST PATH I93
J 0
(-4600 500);
DISPLAY 0.978723 (-4600 500);
PAINT WHITE (-4600 500);
DISPLAY INVISIBLE (-4600 500);
FORCEPROP 2 LAST CDS_LOCATION R4144
J 0
(-4600 550);
DISPLAY 1.021277 (-4600 550);
DISPLAY INVISIBLE (-4600 550);
FORCEPROP 2 LAST $SEC 1
J 0
(-4600 550);
DISPLAY 0.680851 (-4600 550);
PAINT MONO (-4600 550);
DISPLAY INVISIBLE (-4600 550);
FORCEPROP 2 LAST CDS_SEC 1
J 0
(-4600 550);
DISPLAY 1.021277 (-4600 550);
DISPLAY INVISIBLE (-4600 550);
FORCEADD OFFPAGE..1
(-5775 350);
FORCEPROP 2 LAST $XR0 146 
J 0
(-6027 350);
DISPLAY 0.638298 (-6027 350);
PAINT MONO (-6027 350);
FORCEPROP 2 LAST PATH I94
J 0
(-5725 425);
DISPLAY 1.021277 (-5725 425);
DISPLAY INVISIBLE (-5725 425);
FORCEPROP 2 LAST CDS_LIB standard
J 0
(-5775 350);
DISPLAY INVISIBLE (-5775 350);
FORCEPROP 1 LAST COMMENT_BODY TRUE
J 0
(-5650 250);
DISPLAY 1.170213 (-5650 250);
PAINT GREEN (-5650 250);
DISPLAY INVISIBLE (-5650 250);
FORCEPROP 1 LAST OFFPAGE TRUE
J 0
(-5450 225);
DISPLAY 0.872340 (-5450 225);
DISPLAY INVISIBLE (-5450 225);
FORCEADD OFFPAGE..2
(-3175 200);
FORCEPROP 2 LAST $XR0 215 
J 0
(-2986 200);
DISPLAY 0.638298 (-2986 200);
PAINT MONO (-2986 200);
FORCEPROP 1 LAST OFFPAGE TRUE
J 0
(-2850 75);
DISPLAY 0.872340 (-2850 75);
PAINT GREEN (-2850 75);
DISPLAY INVISIBLE (-2850 75);
FORCEPROP 1 LAST COMMENT_BODY TRUE
J 0
(-3220 105);
DISPLAY 0.872340 (-3220 105);
PAINT PEACH (-3220 105);
DISPLAY INVISIBLE (-3220 105);
FORCEPROP 2 LAST CDS_LIB standard
J 0
(-3175 200);
DISPLAY INVISIBLE (-3175 200);
FORCEPROP 2 LAST PATH I95
J 0
(-3000 275);
DISPLAY 1.021277 (-3000 275);
DISPLAY INVISIBLE (-3000 275);
FORCEADD OFFPAGE..2
(-3175 25);
FORCEPROP 2 LAST $XR0 215 
J 0
(-2986 25);
DISPLAY 0.638298 (-2986 25);
PAINT MONO (-2986 25);
FORCEPROP 1 LAST OFFPAGE TRUE
J 0
(-2850 -100);
DISPLAY 0.872340 (-2850 -100);
PAINT GREEN (-2850 -100);
DISPLAY INVISIBLE (-2850 -100);
FORCEPROP 1 LAST COMMENT_BODY TRUE
J 0
(-3220 -70);
DISPLAY 0.872340 (-3220 -70);
PAINT PEACH (-3220 -70);
DISPLAY INVISIBLE (-3220 -70);
FORCEPROP 2 LAST CDS_LIB standard
J 0
(-3175 25);
DISPLAY INVISIBLE (-3175 25);
FORCEPROP 2 LAST PATH I96
J 0
(-3000 100);
DISPLAY 1.021277 (-3000 100);
DISPLAY INVISIBLE (-3000 100);
FORCEADD Q_RES..1
(-4550 200);
FORCEPROP 1 LAST PART_NUMBER CS03322FB03
J 0
(-4700 275);
DISPLAY 0.638298 (-4700 275);
DISPLAY INVISIBLE (-4700 275);
FORCEPROP 1 LAST VALUE 33.2
J 2
(-4300 200);
DISPLAY 0.638298 (-4300 200);
FORCEPROP 1 LAST TOLERANCE 1%
J 0
(-4275 200);
DISPLAY 0.638298 (-4275 200);
FORCEPROP 1 LAST MATERIAL CHIP
J 0
(-4200 200);
DISPLAY 0.638298 (-4200 200);
FORCEPROP 1 LAST $LOCATION R4145
J 0
(-4825 200);
DISPLAY 0.787234 (-4825 200);
FORCEPROP 1 LASTPIN (-4650 200) $PN 1
J 0
(-4638 212);
DISPLAY 0.787234 (-4638 212);
FORCEPROP 1 LASTPIN (-4450 200) $PN 2
J 0
(-4488 212);
DISPLAY 0.787234 (-4488 212);
FORCEPROP 1 LAST PATH I97
J 0
(-4600 350);
DISPLAY 0.978723 (-4600 350);
PAINT WHITE (-4600 350);
DISPLAY INVISIBLE (-4600 350);
FORCEPROP 1 LAST WATTAGE 1/16W
J 2
(-4350 325);
DISPLAY 0.638298 (-4350 325);
DISPLAY INVISIBLE (-4350 325);
FORCEPROP 1 LAST PACK_TYPE 0402LF
J 0
(-4700 325);
DISPLAY 0.638298 (-4700 325);
DISPLAY INVISIBLE (-4700 325);
FORCEPROP 2 LAST CDS_LIB pure_quanta
J 0
(-4550 200);
PAINT MONO (-4550 200);
DISPLAY INVISIBLE (-4550 200);
FORCEPROP 2 LAST CDS_LOCATION R4145
J 0
(-4600 400);
DISPLAY 1.021277 (-4600 400);
DISPLAY INVISIBLE (-4600 400);
FORCEPROP 2 LAST $SEC 1
J 0
(-4600 400);
DISPLAY 0.680851 (-4600 400);
PAINT MONO (-4600 400);
DISPLAY INVISIBLE (-4600 400);
FORCEPROP 2 LAST CDS_SEC 1
J 0
(-4600 400);
DISPLAY 1.021277 (-4600 400);
DISPLAY INVISIBLE (-4600 400);
FORCEADD Q_RES..1
(-4550 25);
FORCEPROP 1 LAST PART_NUMBER CS03322FB03
J 0
(-4700 100);
DISPLAY 0.638298 (-4700 100);
DISPLAY INVISIBLE (-4700 100);
FORCEPROP 1 LAST VALUE 33.2
J 2
(-4300 25);
DISPLAY 0.638298 (-4300 25);
FORCEPROP 1 LAST TOLERANCE 1%
J 0
(-4275 25);
DISPLAY 0.638298 (-4275 25);
FORCEPROP 1 LAST MATERIAL CHIP
J 0
(-4200 25);
DISPLAY 0.638298 (-4200 25);
FORCEPROP 1 LAST $LOCATION R4146
J 0
(-4825 25);
DISPLAY 0.787234 (-4825 25);
FORCEPROP 1 LASTPIN (-4650 25) $PN 1
J 0
(-4638 37);
DISPLAY 0.787234 (-4638 37);
FORCEPROP 1 LASTPIN (-4450 25) $PN 2
J 0
(-4488 37);
DISPLAY 0.787234 (-4488 37);
FORCEPROP 1 LAST PATH I98
J 0
(-4600 175);
DISPLAY 0.978723 (-4600 175);
PAINT WHITE (-4600 175);
DISPLAY INVISIBLE (-4600 175);
FORCEPROP 1 LAST WATTAGE 1/16W
J 2
(-4350 150);
DISPLAY 0.638298 (-4350 150);
DISPLAY INVISIBLE (-4350 150);
FORCEPROP 1 LAST PACK_TYPE 0402LF
J 0
(-4700 150);
DISPLAY 0.638298 (-4700 150);
DISPLAY INVISIBLE (-4700 150);
FORCEPROP 2 LAST CDS_LIB pure_quanta
J 0
(-4550 25);
PAINT MONO (-4550 25);
DISPLAY INVISIBLE (-4550 25);
FORCEPROP 2 LAST CDS_LOCATION R4146
J 0
(-4600 225);
DISPLAY 1.021277 (-4600 225);
DISPLAY INVISIBLE (-4600 225);
FORCEPROP 2 LAST $SEC 1
J 0
(-4600 225);
DISPLAY 0.680851 (-4600 225);
PAINT MONO (-4600 225);
DISPLAY INVISIBLE (-4600 225);
FORCEPROP 2 LAST CDS_SEC 1
J 0
(-4600 225);
DISPLAY 1.021277 (-4600 225);
DISPLAY INVISIBLE (-4600 225);
FORCEADD OFFPAGE..1
(-5775 200);
FORCEPROP 2 LAST $XR1 227 
J 0
(-6027 164);
DISPLAY 0.638298 (-6027 164);
PAINT MONO (-6027 164);
FORCEPROP 2 LAST $XR0 146 
J 0
(-6027 200);
DISPLAY 0.638298 (-6027 200);
PAINT MONO (-6027 200);
FORCEPROP 2 LAST PATH I99
J 0
(-5725 275);
DISPLAY 1.021277 (-5725 275);
DISPLAY INVISIBLE (-5725 275);
FORCEPROP 1 LAST OFFPAGE TRUE
J 0
(-5450 75);
DISPLAY 0.872340 (-5450 75);
DISPLAY INVISIBLE (-5450 75);
FORCEPROP 1 LAST COMMENT_BODY TRUE
J 0
(-5650 100);
DISPLAY 1.170213 (-5650 100);
PAINT GREEN (-5650 100);
DISPLAY INVISIBLE (-5650 100);
FORCEPROP 2 LAST CDS_LIB standard
J 0
(-5775 200);
DISPLAY INVISIBLE (-5775 200);
FORCEADD DNS..2
(975 3625);
PAINT RED (975 3625);
FORCEPROP 1 LAST COMMENT_BODY TRUE
R 1
J 0
(1050 3400);
DISPLAY 0.872340 (1050 3400);
PAINT GREEN (1050 3400);
DISPLAY INVISIBLE (1050 3400);
FORCEPROP 2 LAST CDS_LIB mstr_misc
J 0
(975 3625);
PAINT MONO (975 3625);
DISPLAY INVISIBLE (975 3625);
FORCEADD QUANTA_TITLE_BLOCK_C..1
(3000 -2100);
FORCEPROP 0 LAST CDS_CON_LAST_MODIFIED Fri Aug 25 14:03:34 2023
J 0
(1115 -2085);
PAINT MONO (1115 -2085);
DISPLAY INVISIBLE (1115 -2085);
FORCEPROP 2 LAST CUSTOM_TXT_CDS <XR_PAGE_TITLE>
J 0
(-4890 3150);
DISPLAY 0.638298 (-4890 3150);
PAINT PINK (-4890 3150);
DISPLAY INVISIBLE (-4890 3150);
FORCEPROP 2 LAST CUSTOM_TXT_CDS <CON_LAST_MODIFIED>
J 0
(1115 -2085);
DISPLAY 0.978723 (1115 -2085);
FORCEPROP 2 LAST CUSTOM_TXT_CDS <Q_NUMBER>
J 0
(1597 -1997);
DISPLAY 1.212766 (1597 -1997);
FORCEPROP 2 LAST CUSTOM_TXT_CDS <CON_PAGE_NUM> OF <CON_TOTAL_PAGES>
J 0
(2554 -2082);
DISPLAY 0.978723 (2554 -2082);
FORCEPROP 2 LAST CUSTOM_TXT_CDS <Q_REV>
J 0
(2816 -1997);
DISPLAY 1.212766 (2816 -1997);
FORCEPROP 2 LAST CUSTOM_TXT_CDS <Q_PROJ>
J 0
(618 -1998);
DISPLAY 1.212766 (618 -1998);
FORCEPROP 2 LAST CUSTOM_TXT_CDS <NAME_2>
J 0
(-175 -2050);
FORCEPROP 2 LAST CUSTOM_TXT_CDS <NAME_1>
J 0
(-175 -1925);
FORCEPROP 1 LAST Q_TITLE MAIN FPGA / PFR (3/5)
J 0
(-6341 -2074);
DISPLAY 1.957447 (-6341 -2074);
PAINT GREEN (-6341 -2074);
FORCEPROP 1 LAST Q_DEPT 
J 1
(-763 -2051);
DISPLAY 1.957447 (-763 -2051);
PAINT GREEN (-763 -2051);
FORCEPROP 2 LAST CDS_XR_PAGE_TITLE CR-215 : @S9S_MB_2U_LIB.S9S_MB_2U(SCH_1):PAGE215
J 0
(-4890 3150);
DISPLAY 0.638298 (-4890 3150);
PAINT PINK (-4890 3150);
DISPLAY INVISIBLE (-4890 3150);
FORCEPROP 1 LAST CDS_LMAN_SYM_OUTLINE -9475,6775,100,-125
J 0
(3000 -2100);
DISPLAY 0.468085 (3000 -2100);
PAINT GREEN (3000 -2100);
DISPLAY INVISIBLE (3000 -2100);
FORCEPROP 2 LAST CDS_LIB pure_quanta
J 0
(3000 -2100);
PAINT MONO (3000 -2100);
DISPLAY INVISIBLE (3000 -2100);
FORCEPROP 1 LAST COMMENT_BODY TRUE
J 0
(3012 -2113);
DISPLAY 0.978723 (3012 -2113);
PAINT GREEN (3012 -2113);
DISPLAY INVISIBLE (3012 -2113);
FORCEPROP 2 LAST PAGE_BORDER TRUE
J 0
(-4890 3150);
DISPLAY 0.638298 (-4890 3150);
PAINT PINK (-4890 3150);
DISPLAY INVISIBLE (-4890 3150);
WIRE 16 -1 (975 3750)(975 3850);
WIRE 16 -1 (-6000 4025)(-6000 3975);
WIRE 16 -1 (1775 2600)(1775 2700);
WIRE 16 -1 (1775 2000)(1775 1925);
WIRE 16 -1 (-6000 3225)(-6000 3150);
WIRE 16 -1 (775 1825)(775 1950);
WIRE 16 2175 (-6100 -1050)(-2775 -1050);
WIRE 16 2175 (-2775 600)(-2775 -1050);
WIRE 16 2175 (-6100 600)(-6100 -1050);
WIRE 16 2175 (-6100 600)(-2775 600);
WIRE 16 -1 (-3900 2150)(-2875 2150);
FORCEPROP 0 LAST CDS_PHYS_NET_NAME FM_PLD_HEARTBEAT_LVC3
J 0
(-3875 2192);
PAINT MONO (-3875 2192);
DISPLAY INVISIBLE (-3875 2192);
FORCEPROP 0 LAST SIG_NAME FM_PLD_HEARTBEAT_LVC3
J 0
(-3860 2160);
DISPLAY 0.680851 (-3860 2160);
PAINT WHITE (-3860 2160);
WIRE 16 -1 (-3900 2200)(-2875 2200);
FORCEPROP 0 LAST CDS_PHYS_NET_NAME FM_DEBUG_PORT_PRSNT_N
J 0
(-3875 2242);
PAINT MONO (-3875 2242);
DISPLAY INVISIBLE (-3875 2242);
FORCEPROP 0 LAST SIG_NAME FM_DEBUG_PORT_PRSNT_N
J 0
(-3860 2210);
DISPLAY 0.680851 (-3860 2210);
PAINT WHITE (-3860 2210);
WIRE 16 -1 (-3900 2250)(-2875 2250);
FORCEPROP 0 LAST CDS_PHYS_NET_NAME JTAG_DBP_BMC_PRDY_R_N
J 0
(-3875 2292);
PAINT MONO (-3875 2292);
DISPLAY INVISIBLE (-3875 2292);
FORCEPROP 0 LAST SIG_NAME JTAG_DBP_BMC_PRDY_R_N
J 0
(-3860 2260);
DISPLAY 0.680851 (-3860 2260);
PAINT WHITE (-3860 2260);
WIRE 16 -1 (-3900 1800)(-2875 1800);
FORCEPROP 0 LAST CDS_PHYS_NET_NAME CLK_25M_OSC_MAIN_FPGA
J 0
(-3875 1842);
PAINT MONO (-3875 1842);
DISPLAY INVISIBLE (-3875 1842);
FORCEPROP 0 LAST SIG_NAME CLK_25M_OSC_MAIN_FPGA
J 0
(-3860 1810);
DISPLAY 0.680851 (-3860 1810);
PAINT WHITE (-3860 1810);
WIRE 16 -1 (-3900 1900)(-2875 1900);
FORCEPROP 0 LAST CDS_PHYS_NET_NAME PD_GPP_I_12
J 0
(-3750 1941);
PAINT MONO (-3750 1941);
DISPLAY INVISIBLE (-3750 1941);
FORCEPROP 2 LAST SIG_NAME FM_PCH_BMC_RST_N
J 0
(-3860 1910);
DISPLAY 0.659574 (-3860 1910);
PAINT WHITE (-3860 1910);
WIRE 16 -1 (-3900 2000)(-2875 2000);
FORCEPROP 0 LAST CDS_PHYS_NET_NAME PCIE_M2_SSD0_PRSNT_N
J 0
(-3875 2042);
PAINT MONO (-3875 2042);
DISPLAY INVISIBLE (-3875 2042);
FORCEPROP 0 LAST SIG_NAME HSC_D_OC_R1
J 0
(-3860 2010);
DISPLAY 0.680851 (-3860 2010);
PAINT WHITE (-3860 2010);
WIRE 16 -1 (-3900 2050)(-2875 2050);
FORCEPROP 0 LAST CDS_PHYS_NET_NAME PCIE_M2_SSD0_PRSNT_N
J 0
(-3875 2092);
PAINT MONO (-3875 2092);
DISPLAY INVISIBLE (-3875 2092);
FORCEPROP 0 LAST SIG_NAME E1S_0_PRSNT_N
J 0
(-3860 2060);
DISPLAY 0.680851 (-3860 2060);
PAINT WHITE (-3860 2060);
WIRE 16 -1 (-3900 2100)(-2875 2100);
FORCEPROP 0 LAST CDS_PHYS_NET_NAME FM_FORCE_PWRON_LVC3
J 0
(-3875 2142);
PAINT MONO (-3875 2142);
DISPLAY INVISIBLE (-3875 2142);
FORCEPROP 0 LAST SIG_NAME FM_FORCE_PWRON_LVC3
J 0
(-3860 2110);
DISPLAY 0.680851 (-3860 2110);
PAINT WHITE (-3860 2110);
WIRE 16 -1 (-3900 1950)(-2875 1950);
FORCEPROP 0 LAST CDS_PHYS_NET_NAME BMC_MONITER_R
J 0
(-3585 1990);
PAINT MONO (-3585 1990);
DISPLAY INVISIBLE (-3585 1990);
FORCEPROP 2 LAST SIG_NAME PRSNT_SWB_ISO_R_N
J 0
(-3860 1960);
DISPLAY 0.638298 (-3860 1960);
PAINT WHITE (-3860 1960);
WIRE 16 -1 (-5725 875)(-4650 875);
FORCEPROP 0 LAST CDS_PHYS_NET_NAME BMC_MONITER
J 0
(-5700 917);
PAINT MONO (-5700 917);
DISPLAY INVISIBLE (-5700 917);
FORCEPROP 0 LAST SIG_NAME HSC_D_OC
J 0
(-5625 885);
DISPLAY 0.680851 (-5625 885);
PAINT WHITE (-5625 885);
WIRE 16 -1 (-4450 525)(-3225 525);
FORCEPROP 0 LAST CDS_PHYS_NET_NAME CLK_25M_OSC_MAIN_FPGA
J 0
(-4425 567);
PAINT MONO (-4425 567);
DISPLAY INVISIBLE (-4425 567);
FORCEPROP 0 LAST SIG_NAME GPU_3V3IO_RSVD0_FFU_ISO_R
J 0
(-4060 535);
DISPLAY 0.680851 (-4060 535);
PAINT WHITE (-4060 535);
WIRE 16 -1 (-5725 -1525)(-4650 -1525);
FORCEPROP 0 LAST CDS_PHYS_NET_NAME FM_DEBUG_PORT_PRSNT_N
J 0
(-5700 -1483);
PAINT MONO (-5700 -1483);
DISPLAY INVISIBLE (-5700 -1483);
FORCEPROP 0 LAST SIG_NAME FM_DEBUG_PORT_PRSNT_N
J 0
(-5625 -1515);
DISPLAY 0.680851 (-5625 -1515);
PAINT WHITE (-5625 -1515);
WIRE 16 2175 (-6225 -1625)(-2625 -1625);
WIRE 16 2175 (-2625 -1625)(-2625 -1850);
WIRE 16 2175 (-6225 -1625)(-6225 -1850);
WIRE 16 2175 (-6225 -1850)(-2625 -1850);
WIRE 16 -1 (-4450 -1775)(-3225 -1775);
FORCEPROP 0 LAST CDS_PHYS_NET_NAME PD_GPP_I_12
J 0
(-4300 -1734);
PAINT MONO (-4300 -1734);
DISPLAY INVISIBLE (-4300 -1734);
FORCEPROP 2 LAST SIG_NAME FM_PCH_BMC_RST_N
J 0
(-4010 -1765);
DISPLAY 0.659574 (-4010 -1765);
PAINT WHITE (-4010 -1765);
WIRE 16 -1 (-4450 -1525)(-3225 -1525);
FORCEPROP 0 LAST CDS_PHYS_NET_NAME FM_DEBUG_PORT_PRSNT_R_N
J 0
(-4135 -1485);
PAINT MONO (-4135 -1485);
DISPLAY INVISIBLE (-4135 -1485);
FORCEPROP 2 LAST SIG_NAME FM_DEBUG_PORT_PRSNT_R_N
J 0
(-4035 -1490);
DISPLAY 0.638298 (-4035 -1490);
PAINT WHITE (-4035 -1490);
WIRE 16 -1 (-4450 -1325)(-3225 -1325);
FORCEPROP 0 LAST CDS_PHYS_NET_NAME FM_REMOTE_DEBUG_DET
J 0
(-4135 -1285);
PAINT MONO (-4135 -1285);
DISPLAY INVISIBLE (-4135 -1285);
FORCEPROP 2 LAST SIG_NAME FM_REMOTE_DEBUG_DET
J 0
(-4035 -1290);
DISPLAY 0.638298 (-4035 -1290);
PAINT WHITE (-4035 -1290);
WIRE 16 -1 (-5725 -1775)(-4650 -1775);
FORCEPROP 0 LAST CDS_PHYS_NET_NAME PD_GPP_I_12
J 0
(-5575 -1734);
PAINT MONO (-5575 -1734);
DISPLAY INVISIBLE (-5575 -1734);
FORCEPROP 2 LAST SIG_NAME FM_PCH_BMC_RST_R_N
J 0
(-5500 -1765);
DISPLAY 0.659574 (-5500 -1765);
PAINT WHITE (-5500 -1765);
WIRE 16 -1 (-1900 -1575)(-675 -1575);
FORCEPROP 2 LAST SIG_NAME FM_PDB_BUF_EN
J 0
(-1535 -1565);
DISPLAY 0.638298 (-1535 -1565);
PAINT WHITE (-1535 -1565);
WIRE 16 2175 (-2225 -1650)(-925 -1650);
WIRE 16 2175 (-925 -1475)(-925 -1650);
WIRE 16 2175 (-2225 -1475)(-2225 -1650);
WIRE 16 2175 (-2225 -1475)(-925 -1475);
WIRE 16 -1 (-4450 -950)(-3225 -950);
FORCEPROP 0 LAST CDS_PHYS_NET_NAME CLK_25M_OSC_MAIN_FPGA
J 0
(-4425 -908);
PAINT MONO (-4425 -908);
DISPLAY INVISIBLE (-4425 -908);
FORCEPROP 0 LAST SIG_NAME GPU_3V3IO_RSVD4_ISO_R
J 0
(-4060 -940);
DISPLAY 0.680851 (-4060 -940);
PAINT WHITE (-4060 -940);
WIRE 16 -1 (-1900 -1025)(-675 -1025);
FORCEPROP 0 LAST CDS_PHYS_NET_NAME IRQ_PCH_SCI_WHEA_R_N
J 0
(-1875 -983);
PAINT MONO (-1875 -983);
DISPLAY INVISIBLE (-1875 -983);
FORCEPROP 0 LAST SIG_NAME IRQ_PCH_SCI_WHEA_R_N
J 0
(-1800 -1015);
DISPLAY 0.680851 (-1800 -1015);
PAINT WHITE (-1800 -1015);
WIRE 16 -1 (-1900 -1225)(-675 -1225);
FORCEPROP 0 LAST CDS_PHYS_NET_NAME IRQ_SML1_PMBUS_ALERT_N
J 0
(-1875 -1183);
PAINT MONO (-1875 -1183);
DISPLAY INVISIBLE (-1875 -1183);
FORCEPROP 0 LAST SIG_NAME IRQ_SML1_PMBUS_ALERT_N
J 0
(-1800 -1215);
DISPLAY 0.680851 (-1800 -1215);
PAINT WHITE (-1800 -1215);
WIRE 16 -1 (-3900 1600)(-2875 1600);
FORCEPROP 0 LAST CDS_PHYS_NET_NAME CLK_25M_OSC_MAIN_FPGA
J 0
(-3875 1642);
PAINT MONO (-3875 1642);
DISPLAY INVISIBLE (-3875 1642);
FORCEPROP 0 LAST SIG_NAME PRSNT_CABLE_GPU_B3_ISO_R_N
J 0
(-3860 1610);
DISPLAY 0.680851 (-3860 1610);
PAINT WHITE (-3860 1610);
WIRE 16 -1 (-500 -125)(925 -125);
FORCEPROP 2 LAST SIG_NAME SWB_HSC_PWRGD_ISO
J 0
(-10 -115);
DISPLAY 0.638298 (-10 -115);
PAINT WHITE (-10 -115);
WIRE 16 -1 (-475 175)(900 175);
FORCEPROP 0 LAST CDS_PHYS_NET_NAME BMC_MONITER_R
J 0
(-160 215);
PAINT MONO (-160 215);
DISPLAY INVISIBLE (-160 215);
FORCEPROP 2 LAST SIG_NAME SWB_HSC_EN_R
J 0
(-10 185);
DISPLAY 0.638298 (-10 185);
PAINT WHITE (-10 185);
WIRE 16 -1 (-675 -450)(-1900 -450);
FORCEPROP 2 LAST SIG_NAME IRQ_UV_DETECT_N
J 0
(-1810 -440);
DISPLAY 0.638298 (-1810 -440);
PAINT WHITE (-1810 -440);
WIRE 16 -1 (-675 -675)(-1900 -675);
FORCEPROP 2 LAST SIG_NAME FM_UV_ADR_TRIGGER_N
J 0
(-1810 -665);
DISPLAY 0.638298 (-1810 -665);
PAINT WHITE (-1810 -665);
WIRE 16 -1 (-1900 -850)(-675 -850);
FORCEPROP 0 LAST CDS_PHYS_NET_NAME FM_ADR_ACK_R
J 0
(-1875 -808);
PAINT MONO (-1875 -808);
DISPLAY INVISIBLE (-1875 -808);
FORCEPROP 0 LAST SIG_NAME FM_ADR_ACK_R
J 0
(-1800 -840);
DISPLAY 0.680851 (-1800 -840);
PAINT WHITE (-1800 -840);
WIRE 16 -1 (-675 -1400)(-1900 -1400);
FORCEPROP 0 LAST CDS_PHYS_NET_NAME FM_BMC_READY_R_PLD_N
J 0
(-1875 -1358);
PAINT MONO (-1875 -1358);
DISPLAY INVISIBLE (-1875 -1358);
FORCEPROP 0 LAST SIG_NAME FM_BMC_READY_R_PLD_N
J 0
(-1800 -1390);
DISPLAY 0.680851 (-1800 -1390);
PAINT WHITE (-1800 -1390);
WIRE 16 -1 (-5725 -1325)(-4650 -1325);
FORCEPROP 0 LAST CDS_PHYS_NET_NAME FM_REMOTE_DEBUG_DET_R
J 0
(-5700 -1283);
PAINT MONO (-5700 -1283);
DISPLAY INVISIBLE (-5700 -1283);
FORCEPROP 0 LAST SIG_NAME FM_REMOTE_DEBUG_DET_R
J 0
(-5625 -1315);
DISPLAY 0.680851 (-5625 -1315);
PAINT WHITE (-5625 -1315);
WIRE 16 -1 (-1125 3100)(-125 3100);
FORCEPROP 0 LAST CDS_PHYS_NET_NAME PWRGD_SYS_PWROK_R
J 0
(-1100 3142);
PAINT MONO (-1100 3142);
DISPLAY INVISIBLE (-1100 3142);
FORCEPROP 0 LAST SIG_NAME NC_FPGA_PB32D
J 0
(-985 3110);
DISPLAY 0.680851 (-985 3110);
PAINT WHITE (-985 3110);
WIRE 16 -1 (-3900 2700)(-2875 2700);
FORCEPROP 0 LAST CDS_PHYS_NET_NAME FM_BMC_DBP_PRESENT_R_N
J 0
(-3875 2742);
PAINT MONO (-3875 2742);
DISPLAY INVISIBLE (-3875 2742);
FORCEPROP 0 LAST SIG_NAME FM_BMC_DBP_PRESENT_R_N
J 0
(-3860 2710);
DISPLAY 0.680851 (-3860 2710);
PAINT WHITE (-3860 2710);
WIRE 16 -1 (-3900 2750)(-2875 2750);
FORCEPROP 0 LAST CDS_PHYS_NET_NAME FM_REMOTE_DEBUG_DET
J 0
(-3875 2792);
PAINT MONO (-3875 2792);
DISPLAY INVISIBLE (-3875 2792);
FORCEPROP 0 LAST SIG_NAME FM_REMOTE_DEBUG_DET
J 0
(-3860 2760);
DISPLAY 0.680851 (-3860 2760);
PAINT WHITE (-3860 2760);
WIRE 16 -1 (-1125 3050)(-125 3050);
FORCEPROP 0 LAST CDS_PHYS_NET_NAME RST_PLTRST_PLD_B_N
J 0
(-1100 3092);
PAINT MONO (-1100 3092);
DISPLAY INVISIBLE (-1100 3092);
FORCEPROP 0 LAST SIG_NAME RST_PLTRST_PLD_B_N
J 0
(-985 3060);
DISPLAY 0.680851 (-985 3060);
PAINT WHITE (-985 3060);
WIRE 16 -1 (-1125 3200)(-125 3200);
FORCEPROP 0 LAST CDS_PHYS_NET_NAME FM_ME_BT_DONE
J 0
(-1100 3242);
PAINT MONO (-1100 3242);
DISPLAY INVISIBLE (-1100 3242);
FORCEPROP 0 LAST SIG_NAME FM_ME_BT_DONE
J 0
(-985 3210);
DISPLAY 0.680851 (-985 3210);
PAINT WHITE (-985 3210);
WIRE 16 -1 (-1125 3250)(-125 3250);
FORCEPROP 0 LAST CDS_PHYS_NET_NAME RST_SGPIO_RESET_N_R
J 0
(-1100 3292);
PAINT MONO (-1100 3292);
DISPLAY INVISIBLE (-1100 3292);
FORCEPROP 0 LAST SIG_NAME RST_SGPIO_RESET_N_R
J 0
(-985 3260);
DISPLAY 0.680851 (-985 3260);
PAINT WHITE (-985 3260);
WIRE 16 -1 (-1125 3350)(-125 3350);
FORCEPROP 0 LAST CDS_PHYS_NET_NAME IRQ_PSU_ALERT_R_N
J 0
(-1100 3392);
PAINT MONO (-1100 3392);
DISPLAY INVISIBLE (-1100 3392);
FORCEPROP 0 LAST SIG_NAME IRQ_PSU_ALERT_R_N
J 0
(-985 3360);
DISPLAY 0.680851 (-985 3360);
PAINT WHITE (-985 3360);
WIRE 16 -1 (-1125 3300)(-125 3300);
FORCEPROP 0 LAST CDS_PHYS_NET_NAME IRQ_PCH_SCI_WHEA_R_N
J 0
(-1100 3342);
PAINT MONO (-1100 3342);
DISPLAY INVISIBLE (-1100 3342);
FORCEPROP 0 LAST SIG_NAME IRQ_PCH_SCI_WHEA_R_N
J 0
(-985 3310);
DISPLAY 0.680851 (-985 3310);
PAINT WHITE (-985 3310);
WIRE 16 -1 (-1125 3450)(-125 3450);
FORCEPROP 0 LAST CDS_PHYS_NET_NAME IRQ_TPM_SPI_N
J 0
(-1100 3492);
PAINT MONO (-1100 3492);
DISPLAY INVISIBLE (-1100 3492);
FORCEPROP 0 LAST SIG_NAME IRQ_TPM_SPI_N
J 0
(-985 3460);
DISPLAY 0.680851 (-985 3460);
PAINT WHITE (-985 3460);
WIRE 16 -1 (-1125 3400)(-125 3400);
FORCEPROP 0 LAST CDS_PHYS_NET_NAME IRQ_PVCCD_CPU1_VRHOT_LVC3_N
J 0
(-1100 3442);
PAINT MONO (-1100 3442);
DISPLAY INVISIBLE (-1100 3442);
FORCEPROP 0 LAST SIG_NAME IRQ_PVCCD_CPU1_VRHOT_LVC3_N
J 0
(-985 3410);
DISPLAY 0.680851 (-985 3410);
PAINT WHITE (-985 3410);
WIRE 16 -1 (-1125 3550)(-150 3550);
FORCEPROP 0 LAST CDS_PHYS_NET_NAME IRQ_PCH_CPU_NMI_EVENT_N
J 0
(-1100 3592);
PAINT MONO (-1100 3592);
DISPLAY INVISIBLE (-1100 3592);
FORCEPROP 0 LAST SIG_NAME IRQ_PCH_CPU_NMI_EVENT_N
J 0
(-985 3560);
DISPLAY 0.680851 (-985 3560);
PAINT WHITE (-985 3560);
WIRE 16 -1 (-1125 3600)(-150 3600);
FORCEPROP 0 LAST CDS_PHYS_NET_NAME IRQ_PSYS_CRIT_N
J 0
(-1100 3642);
PAINT MONO (-1100 3642);
DISPLAY INVISIBLE (-1100 3642);
FORCEPROP 0 LAST SIG_NAME IRQ_PSYS_CRIT_N
J 0
(-985 3610);
DISPLAY 0.680851 (-985 3610);
PAINT WHITE (-985 3610);
WIRE 16 -1 (-1125 3650)(-150 3650);
FORCEPROP 0 LAST CDS_PHYS_NET_NAME IRQ_SGPIO_INTR_N_R
J 0
(-1100 3692);
PAINT MONO (-1100 3692);
DISPLAY INVISIBLE (-1100 3692);
FORCEPROP 0 LAST SIG_NAME IRQ_SGPIO_INTR_N_R
J 0
(-985 3660);
DISPLAY 0.680851 (-985 3660);
PAINT WHITE (-985 3660);
WIRE 16 -1 (-475 -675)(950 -675);
FORCEPROP 0 LAST CDS_PHYS_NET_NAME FM_UV_ADR_TRIGGER_R_N
J 0
(-160 -635);
PAINT MONO (-160 -635);
DISPLAY INVISIBLE (-160 -635);
FORCEPROP 2 LAST SIG_NAME FM_UV_ADR_TRIGGER_R_N
J 0
(-135 -665);
DISPLAY 0.638298 (-135 -665);
PAINT WHITE (-135 -665);
WIRE 16 -1 (-3900 3850)(-2875 3850);
FORCEPROP 0 LAST CDS_PHYS_NET_NAME FM_ADR_ACK_R
J 0
(-3875 3892);
PAINT MONO (-3875 3892);
DISPLAY INVISIBLE (-3875 3892);
FORCEPROP 0 LAST SIG_NAME FM_ADR_ACK_R
J 0
(-3860 3860);
DISPLAY 0.680851 (-3860 3860);
PAINT WHITE (-3860 3860);
WIRE 16 -1 (-6000 3625)(-6000 3775);
WIRE 16 -1 (-5250 3625)(-6000 3625);
FORCEPROP 0 LAST CDS_PHYS_NET_NAME FM_ADR_ACK_R
J 0
(-5975 3667);
PAINT MONO (-5975 3667);
DISPLAY INVISIBLE (-5975 3667);
FORCEPROP 0 LAST SIG_NAME PU_FORCE_PWRON
J 0
(-5960 3635);
DISPLAY 0.680851 (-5960 3635);
PAINT WHITE (-5960 3635);
WIRE 16 -1 (-6025 3575)(-5250 3575);
FORCEPROP 0 LAST CDS_PHYS_NET_NAME FM_FORCE_PWRON_LVC3
J 0
(-6000 3617);
PAINT MONO (-6000 3617);
DISPLAY INVISIBLE (-6000 3617);
FORCEPROP 0 LAST SIG_NAME FM_FORCE_PWRON_LVC3
J 0
(-5960 3585);
DISPLAY 0.680851 (-5960 3585);
PAINT WHITE (-5960 3585);
WIRE 16 -1 (-3900 3300)(-2875 3300);
FORCEPROP 0 LAST CDS_PHYS_NET_NAME FM_PLD_CLK_25M_R_EN
J 0
(-3875 3342);
PAINT MONO (-3875 3342);
DISPLAY INVISIBLE (-3875 3342);
FORCEPROP 0 LAST SIG_NAME FM_PLD_CLK_25M_R_EN
J 0
(-3860 3310);
DISPLAY 0.680851 (-3860 3310);
PAINT WHITE (-3860 3310);
WIRE 16 -1 (-6000 3525)(-6000 3425);
WIRE 16 -1 (-6000 3525)(-5250 3525);
FORCEPROP 0 LAST CDS_PHYS_NET_NAME FM_ADR_ACK_R
J 0
(-5975 3567);
PAINT MONO (-5975 3567);
DISPLAY INVISIBLE (-5975 3567);
FORCEPROP 0 LAST SIG_NAME PD_FORCE_PWRON
J 0
(-5960 3535);
DISPLAY 0.680851 (-5960 3535);
PAINT WHITE (-5960 3535);
WIRE 16 -1 (-1125 3150)(-125 3150);
FORCEPROP 0 LAST CDS_PHYS_NET_NAME RST_PCIE_PCH_DEV_PERST_N
J 0
(-1100 3192);
PAINT MONO (-1100 3192);
DISPLAY INVISIBLE (-1100 3192);
FORCEPROP 0 LAST SIG_NAME RST_PCIE_PCH_DEV_PERST_N
J 0
(-985 3160);
DISPLAY 0.680851 (-985 3160);
PAINT WHITE (-985 3160);
WIRE 16 -1 (-1125 2650)(-125 2650);
FORCEPROP 0 LAST CDS_PHYS_NET_NAME VIRTUAL_RESEAT
J 0
(-1100 2692);
PAINT MONO (-1100 2692);
DISPLAY INVISIBLE (-1100 2692);
FORCEPROP 0 LAST SIG_NAME VIRTUAL_RESEAT
J 0
(-985 2660);
DISPLAY 0.680851 (-985 2660);
PAINT WHITE (-985 2660);
WIRE 16 -1 (-1875 350)(-675 350);
FORCEPROP 0 LAST CDS_PHYS_NET_NAME BMC_MONITER
J 0
(-1850 392);
PAINT MONO (-1850 392);
DISPLAY INVISIBLE (-1850 392);
FORCEPROP 0 LAST SIG_NAME HPDB_HSC_PWRGD_ISO
J 0
(-1775 360);
DISPLAY 0.680851 (-1775 360);
PAINT WHITE (-1775 360);
WIRE 16 -1 (-3900 3650)(-2875 3650);
FORCEPROP 0 LAST CDS_PHYS_NET_NAME FM_ADR_MODE0_R
J 0
(-3875 3692);
PAINT MONO (-3875 3692);
DISPLAY INVISIBLE (-3875 3692);
FORCEPROP 0 LAST SIG_NAME FM_ADR_MODE0_R
J 0
(-3860 3660);
DISPLAY 0.680851 (-3860 3660);
PAINT WHITE (-3860 3660);
WIRE 16 -1 (-3900 3150)(-2875 3150);
FORCEPROP 0 LAST CDS_PHYS_NET_NAME PCIE_M2_SSD0_PRSNT_N
J 0
(-3875 3192);
PAINT MONO (-3875 3192);
DISPLAY INVISIBLE (-3875 3192);
FORCEPROP 0 LAST SIG_NAME PCIE_M2_SSD0_PRSNT_N
J 0
(-3860 3160);
DISPLAY 0.680851 (-3860 3160);
PAINT WHITE (-3860 3160);
WIRE 16 -1 (-3900 3050)(-2875 3050);
FORCEPROP 0 LAST CDS_PHYS_NET_NAME RST_MB_STBY_R_N
J 0
(-3875 3092);
PAINT MONO (-3875 3092);
DISPLAY INVISIBLE (-3875 3092);
FORCEPROP 0 LAST SIG_NAME RST_MB_STBY_R_N
J 0
(-3860 3060);
DISPLAY 0.680851 (-3860 3060);
PAINT WHITE (-3860 3060);
WIRE 16 -1 (-1125 2600)(-125 2600);
FORCEPROP 0 LAST CDS_PHYS_NET_NAME FM_PCH_PLD_GLB_RST_WARN_N
J 0
(-1100 2642);
PAINT MONO (-1100 2642);
DISPLAY INVISIBLE (-1100 2642);
FORCEPROP 0 LAST SIG_NAME FM_PCH_PLD_GLB_RST_WARN_N
J 0
(-985 2610);
DISPLAY 0.680851 (-985 2610);
PAINT WHITE (-985 2610);
WIRE 16 -1 (-3900 2350)(-2875 2350);
FORCEPROP 0 LAST CDS_PHYS_NET_NAME FM_ME_AUTHN_FAIL
J 0
(-3875 2392);
PAINT MONO (-3875 2392);
DISPLAY INVISIBLE (-3875 2392);
FORCEPROP 0 LAST SIG_NAME FM_ME_AUTHN_FAIL
J 0
(-3860 2360);
DISPLAY 0.680851 (-3860 2360);
PAINT WHITE (-3860 2360);
WIRE 16 -1 (-3900 2900)(-2875 2900);
FORCEPROP 0 LAST CDS_PHYS_NET_NAME RST_PFR_OVR_SRTC_R
J 0
(-3875 2942);
PAINT MONO (-3875 2942);
DISPLAY INVISIBLE (-3875 2942);
FORCEPROP 0 LAST SIG_NAME RST_PFR_OVR_SRTC_R
J 0
(-3860 2910);
DISPLAY 0.680851 (-3860 2910);
PAINT WHITE (-3860 2910);
WIRE 16 -1 (-3900 2850)(-2875 2850);
FORCEPROP 0 LAST CDS_PHYS_NET_NAME FM_DIS_PS_PWROK_DLY
J 0
(-3875 2892);
PAINT MONO (-3875 2892);
DISPLAY INVISIBLE (-3875 2892);
FORCEPROP 0 LAST SIG_NAME FM_DIS_PS_PWROK_DLY
J 0
(-3860 2860);
DISPLAY 0.680851 (-3860 2860);
PAINT WHITE (-3860 2860);
WIRE 16 -1 (-3900 2650)(-2875 2650);
FORCEPROP 0 LAST CDS_PHYS_NET_NAME FM_BIOS_POST_CMPLT_BMC_N
J 0
(-3875 2692);
PAINT MONO (-3875 2692);
DISPLAY INVISIBLE (-3875 2692);
FORCEPROP 0 LAST SIG_NAME FM_BIOS_POST_CMPLT_BMC_N
J 0
(-3860 2660);
DISPLAY 0.680851 (-3860 2660);
PAINT WHITE (-3860 2660);
WIRE 16 -1 (-3900 2550)(-2875 2550);
FORCEPROP 0 LAST CDS_PHYS_NET_NAME FM_PS_PWROK_DLY_SEL
J 0
(-3875 2592);
PAINT MONO (-3875 2592);
DISPLAY INVISIBLE (-3875 2592);
FORCEPROP 0 LAST SIG_NAME FM_PS_PWROK_DLY_SEL
J 0
(-3860 2560);
DISPLAY 0.680851 (-3860 2560);
PAINT WHITE (-3860 2560);
WIRE 16 -1 (-3900 2500)(-2875 2500);
FORCEPROP 0 LAST CDS_PHYS_NET_NAME FM_RST_PERST_BIT2
J 0
(-3875 2542);
PAINT MONO (-3875 2542);
DISPLAY INVISIBLE (-3875 2542);
FORCEPROP 0 LAST SIG_NAME FM_RST_PERST_BIT2
J 0
(-3860 2510);
DISPLAY 0.680851 (-3860 2510);
PAINT WHITE (-3860 2510);
WIRE 16 -1 (-3900 2450)(-2875 2450);
FORCEPROP 0 LAST CDS_PHYS_NET_NAME FM_CPU_RMCA_CATERR_LVT3_R_N
J 0
(-3875 2492);
PAINT MONO (-3875 2492);
DISPLAY INVISIBLE (-3875 2492);
FORCEPROP 0 LAST SIG_NAME FM_CPU_RMCA_CATERR_LVT3_R_N
J 0
(-3860 2460);
DISPLAY 0.680851 (-3860 2460);
PAINT WHITE (-3860 2460);
WIRE 16 -1 (-3900 2400)(-2875 2400);
FORCEPROP 0 LAST CDS_PHYS_NET_NAME FM_PCH_BMC_THERMTRIP_N
J 0
(-3875 2442);
PAINT MONO (-3875 2442);
DISPLAY INVISIBLE (-3875 2442);
FORCEPROP 0 LAST SIG_NAME FM_PCH_BMC_THERMTRIP_N
J 0
(-3860 2410);
DISPLAY 0.680851 (-3860 2410);
PAINT WHITE (-3860 2410);
WIRE 16 -1 (-3900 2600)(-2875 2600);
FORCEPROP 0 LAST CDS_PHYS_NET_NAME FM_BMC_RSTBTN_OUT_N
J 0
(-3875 2642);
PAINT MONO (-3875 2642);
DISPLAY INVISIBLE (-3875 2642);
FORCEPROP 0 LAST SIG_NAME FM_BMC_RSTBTN_OUT_N
J 0
(-3860 2610);
DISPLAY 0.680851 (-3860 2610);
PAINT WHITE (-3860 2610);
WIRE 16 -1 (-3900 2800)(-2875 2800);
FORCEPROP 0 LAST CDS_PHYS_NET_NAME FM_PCH_CRASHLOG_TRIG_R_N
J 0
(-3875 2842);
PAINT MONO (-3875 2842);
DISPLAY INVISIBLE (-3875 2842);
FORCEPROP 0 LAST SIG_NAME FM_PCH_CRASHLOG_TRIG_R_N
J 0
(-3860 2810);
DISPLAY 0.680851 (-3860 2810);
PAINT WHITE (-3860 2810);
WIRE 16 -1 (-3900 2950)(-2875 2950);
FORCEPROP 0 LAST CDS_PHYS_NET_NAME RST_PFR_OVR_RTC_R
J 0
(-3875 2992);
PAINT MONO (-3875 2992);
DISPLAY INVISIBLE (-3875 2992);
FORCEPROP 0 LAST SIG_NAME RST_PFR_OVR_RTC_R
J 0
(-3860 2960);
DISPLAY 0.680851 (-3860 2960);
PAINT WHITE (-3860 2960);
WIRE 16 -1 (-3900 3000)(-2875 3000);
FORCEPROP 0 LAST CDS_PHYS_NET_NAME RST_SMB_SWITCH_N
J 0
(-3875 3042);
PAINT MONO (-3875 3042);
DISPLAY INVISIBLE (-3875 3042);
FORCEPROP 0 LAST SIG_NAME RST_SMB_SWITCH_N
J 0
(-3860 3010);
DISPLAY 0.680851 (-3860 3010);
PAINT WHITE (-3860 3010);
WIRE 16 -1 (-3900 3100)(-2875 3100);
FORCEPROP 0 LAST CDS_PHYS_NET_NAME FM_HBM2_HBM3_VPP_SEL
J 0
(-3875 3142);
PAINT MONO (-3875 3142);
DISPLAY INVISIBLE (-3875 3142);
FORCEPROP 0 LAST SIG_NAME FM_HBM2_HBM3_VPP_SEL
J 0
(-3860 3110);
DISPLAY 0.680851 (-3860 3110);
PAINT WHITE (-3860 3110);
WIRE 16 -1 (-3900 3450)(-2875 3450);
FORCEPROP 0 LAST CDS_PHYS_NET_NAME IRQ_PVCCD_CPU0_VRHOT_LVC3_N
J 0
(-3875 3492);
PAINT MONO (-3875 3492);
DISPLAY INVISIBLE (-3875 3492);
FORCEPROP 0 LAST SIG_NAME IRQ_PVCCD_CPU0_VRHOT_LVC3_N
J 0
(-3860 3460);
DISPLAY 0.680851 (-3860 3460);
PAINT WHITE (-3860 3460);
WIRE 16 -1 (-3900 3800)(-2875 3800);
FORCEPROP 0 LAST CDS_PHYS_NET_NAME FM_UV_ADR_TRIGGER_R_N
J 0
(-3875 3842);
PAINT MONO (-3875 3842);
DISPLAY INVISIBLE (-3875 3842);
FORCEPROP 0 LAST SIG_NAME FM_UV_ADR_TRIGGER_R_N
J 0
(-3860 3810);
DISPLAY 0.680851 (-3860 3810);
PAINT WHITE (-3860 3810);
WIRE 16 -1 (-3900 3750)(-2875 3750);
FORCEPROP 0 LAST CDS_PHYS_NET_NAME FM_ADR_TRIGGER_N
J 0
(-3875 3792);
PAINT MONO (-3875 3792);
DISPLAY INVISIBLE (-3875 3792);
FORCEPROP 0 LAST SIG_NAME FM_ADR_TRIGGER_N
J 0
(-3860 3760);
DISPLAY 0.680851 (-3860 3760);
PAINT WHITE (-3860 3760);
WIRE 16 -1 (-3900 3700)(-2875 3700);
FORCEPROP 0 LAST CDS_PHYS_NET_NAME FM_ADR_COMPLETE
J 0
(-3875 3742);
PAINT MONO (-3875 3742);
DISPLAY INVISIBLE (-3875 3742);
FORCEPROP 0 LAST SIG_NAME FM_ADR_COMPLETE
J 0
(-3860 3710);
DISPLAY 0.680851 (-3860 3710);
PAINT WHITE (-3860 3710);
WIRE 16 -1 (-3900 3600)(-2875 3600);
FORCEPROP 0 LAST CDS_PHYS_NET_NAME FM_ADR_MODE1_R
J 0
(-3875 3642);
PAINT MONO (-3875 3642);
DISPLAY INVISIBLE (-3875 3642);
FORCEPROP 0 LAST SIG_NAME FM_ADR_MODE1_R
J 0
(-3860 3610);
DISPLAY 0.680851 (-3860 3610);
PAINT WHITE (-3860 3610);
WIRE 16 -1 (-3900 3550)(-2875 3550);
FORCEPROP 0 LAST CDS_PHYS_NET_NAME IRQ_UV_DETECT_R_N
J 0
(-3875 3592);
PAINT MONO (-3875 3592);
DISPLAY INVISIBLE (-3875 3592);
FORCEPROP 0 LAST SIG_NAME IRQ_UV_DETECT_R_N
J 0
(-3860 3560);
DISPLAY 0.680851 (-3860 3560);
PAINT WHITE (-3860 3560);
WIRE 16 -1 (-3875 3500)(-2875 3500);
FORCEPROP 0 LAST CDS_PHYS_NET_NAME PWRGD_SYS_PWROK_R
J 0
(-3850 3542);
PAINT MONO (-3850 3542);
DISPLAY INVISIBLE (-3850 3542);
FORCEPROP 0 LAST SIG_NAME NC_FPGA_PB7D
J 0
(-3835 3510);
DISPLAY 0.680851 (-3835 3510);
PAINT WHITE (-3835 3510);
WIRE 16 -1 (-3900 3400)(-2875 3400);
FORCEPROP 0 LAST CDS_PHYS_NET_NAME IRQ_BMC_PCH_NMI_R
J 0
(-3875 3442);
PAINT MONO (-3875 3442);
DISPLAY INVISIBLE (-3875 3442);
FORCEPROP 0 LAST SIG_NAME IRQ_BMC_PCH_NMI_R
J 0
(-3860 3410);
DISPLAY 0.680851 (-3860 3410);
PAINT WHITE (-3860 3410);
WIRE 16 -1 (-3900 3350)(-2875 3350);
FORCEPROP 0 LAST CDS_PHYS_NET_NAME FM_PLD_CLKS_DEV_R_EN
J 0
(-3875 3392);
PAINT MONO (-3875 3392);
DISPLAY INVISIBLE (-3875 3392);
FORCEPROP 0 LAST SIG_NAME FM_PLD_CLKS_DEV_R_EN
J 0
(-3860 3360);
DISPLAY 0.680851 (-3860 3360);
PAINT WHITE (-3860 3360);
WIRE 16 -1 (-3900 3250)(-2875 3250);
FORCEPROP 0 LAST CDS_PHYS_NET_NAME PWRGD_PLT_AUX_CPU0_LVT3_R
J 0
(-3875 3292);
PAINT MONO (-3875 3292);
DISPLAY INVISIBLE (-3875 3292);
FORCEPROP 0 LAST SIG_NAME PWRGD_PLT_AUX_CPU0_LVT3_R
J 0
(-3860 3260);
DISPLAY 0.680851 (-3860 3260);
PAINT WHITE (-3860 3260);
WIRE 16 -1 (-3900 3200)(-2875 3200);
FORCEPROP 0 LAST CDS_PHYS_NET_NAME PWRGD_PLT_AUX_CPU1_LVT3_R
J 0
(-3875 3242);
PAINT MONO (-3875 3242);
DISPLAY INVISIBLE (-3875 3242);
FORCEPROP 0 LAST SIG_NAME PWRGD_PLT_AUX_CPU1_LVT3_R
J 0
(-3860 3210);
DISPLAY 0.680851 (-3860 3210);
PAINT WHITE (-3860 3210);
WIRE 16 -1 (-1125 3000)(-125 3000);
FORCEPROP 0 LAST CDS_PHYS_NET_NAME FM_SYS_THROTTLE_R_N
J 0
(-1100 3042);
PAINT MONO (-1100 3042);
DISPLAY INVISIBLE (-1100 3042);
FORCEPROP 0 LAST SIG_NAME FM_SYS_THROTTLE_R_N
J 0
(-985 3010);
DISPLAY 0.680851 (-985 3010);
PAINT WHITE (-985 3010);
WIRE 16 -1 (-1125 2950)(-125 2950);
FORCEPROP 0 LAST CDS_PHYS_NET_NAME FM_NCSI_OCP_V3_1_R_OE
J 0
(-1100 2992);
PAINT MONO (-1100 2992);
DISPLAY INVISIBLE (-1100 2992);
FORCEPROP 0 LAST SIG_NAME FM_NCSI_OCP_V3_1_R_OE
J 0
(-985 2960);
DISPLAY 0.680851 (-985 2960);
PAINT WHITE (-985 2960);
WIRE 16 -1 (-1125 2900)(-125 2900);
FORCEPROP 0 LAST CDS_PHYS_NET_NAME FM_BIOS_DEBUG_EN_N
J 0
(-1100 2942);
PAINT MONO (-1100 2942);
DISPLAY INVISIBLE (-1100 2942);
FORCEPROP 0 LAST SIG_NAME FM_BIOS_DEBUG_EN_N
J 0
(-985 2910);
DISPLAY 0.680851 (-985 2910);
PAINT WHITE (-985 2910);
WIRE 16 -1 (975 3550)(975 3500);
WIRE 16 -1 (-1125 3500)(975 3500);
FORCEPROP 0 LAST CDS_PHYS_NET_NAME IRQ_BMC_CPU_NMI_R1
J 0
(-1100 3542);
PAINT MONO (-1100 3542);
DISPLAY INVISIBLE (-1100 3542);
FORCEPROP 0 LAST SIG_NAME IRQ_BMC_CPU_NMI_R1
J 0
(-985 3510);
DISPLAY 0.680851 (-985 3510);
PAINT WHITE (-985 3510);
WIRE 16 -1 (-1125 2700)(-125 2700);
FORCEPROP 0 LAST CDS_PHYS_NET_NAME FM_DIMM_12V_CPS_SX_N
J 0
(-1100 2742);
PAINT MONO (-1100 2742);
DISPLAY INVISIBLE (-1100 2742);
FORCEPROP 0 LAST SIG_NAME FM_DIMM_12V_CPS_SX_N
J 0
(-985 2710);
DISPLAY 0.680851 (-985 2710);
PAINT WHITE (-985 2710);
WIRE 16 -1 (-1125 2550)(-125 2550);
FORCEPROP 0 LAST CDS_PHYS_NET_NAME ROT_P1_RST_IND_N_R
J 0
(-1100 2592);
PAINT MONO (-1100 2592);
DISPLAY INVISIBLE (-1100 2592);
FORCEPROP 0 LAST SIG_NAME ROT_P1_RST_IND_N_R
J 0
(-985 2560);
DISPLAY 0.680851 (-985 2560);
PAINT WHITE (-985 2560);
WIRE 16 -1 (-1125 2450)(-125 2450);
FORCEPROP 0 LAST CDS_PHYS_NET_NAME FM_PCHHOT_R_N
J 0
(-1100 2492);
PAINT MONO (-1100 2492);
DISPLAY INVISIBLE (-1100 2492);
FORCEPROP 0 LAST SIG_NAME FM_PCHHOT_R_N
J 0
(-985 2460);
DISPLAY 0.680851 (-985 2460);
PAINT WHITE (-985 2460);
WIRE 16 -1 (-1125 2350)(-125 2350);
FORCEPROP 0 LAST CDS_PHYS_NET_NAME RST_PLTRST_PLD_N
J 0
(-1100 2392);
PAINT MONO (-1100 2392);
DISPLAY INVISIBLE (-1100 2392);
FORCEPROP 0 LAST SIG_NAME RST_PLTRST_PLD_N
J 0
(-985 2360);
DISPLAY 0.680851 (-985 2360);
PAINT WHITE (-985 2360);
WIRE 16 -1 (-1125 2500)(-125 2500);
FORCEPROP 0 LAST CDS_PHYS_NET_NAME FM_SLPS3_PLD_N
J 0
(-1100 2542);
PAINT MONO (-1100 2542);
DISPLAY INVISIBLE (-1100 2542);
FORCEPROP 0 LAST SIG_NAME FM_SLPS3_PLD_N
J 0
(-985 2510);
DISPLAY 0.680851 (-985 2510);
PAINT WHITE (-985 2510);
WIRE 16 2175 (-5300 4050)(-4400 4050);
WIRE 16 2175 (-4400 4050)(-4400 3350);
WIRE 16 2175 (-5300 4050)(-5300 3350);
WIRE 16 2175 (-5300 3350)(-4400 3350);
WIRE 16 -1 (-1125 1800)(-125 1800);
FORCEPROP 0 LAST CDS_PHYS_NET_NAME PWRGD_SYS_PWROK_R
J 0
(-1100 1842);
PAINT MONO (-1100 1842);
DISPLAY INVISIBLE (-1100 1842);
FORCEPROP 0 LAST SIG_NAME HPDB_HSC_PWRGD_ISO_R
J 0
(-985 1810);
DISPLAY 0.680851 (-985 1810);
PAINT WHITE (-985 1810);
WIRE 16 -1 (-1125 2300)(-125 2300);
FORCEPROP 0 LAST CDS_PHYS_NET_NAME RST_RSMRST_PLD_R_N
J 0
(-1100 2342);
PAINT MONO (-1100 2342);
DISPLAY INVISIBLE (-1100 2342);
FORCEPROP 0 LAST SIG_NAME RST_RSMRST_PLD_R_N
J 0
(-985 2310);
DISPLAY 0.680851 (-985 2310);
PAINT WHITE (-985 2310);
WIRE 16 -1 (-475 -450)(950 -450);
FORCEPROP 0 LAST CDS_PHYS_NET_NAME IRQ_UV_DETECT_R_N
J 0
(-160 -410);
PAINT MONO (-160 -410);
DISPLAY INVISIBLE (-160 -410);
FORCEPROP 2 LAST SIG_NAME IRQ_UV_DETECT_R_N
J 0
(-110 -440);
DISPLAY 0.638298 (-110 -440);
PAINT WHITE (-110 -440);
WIRE 16 -1 (-475 -850)(950 -850);
FORCEPROP 0 LAST CDS_PHYS_NET_NAME FM_ADR_ACK
J 0
(-450 -808);
PAINT MONO (-450 -808);
DISPLAY INVISIBLE (-450 -808);
FORCEPROP 0 LAST SIG_NAME FM_ADR_ACK
J 0
(-135 -840);
DISPLAY 0.680851 (-135 -840);
PAINT WHITE (-135 -840);
WIRE 16 -1 (-475 -1025)(950 -1025);
FORCEPROP 0 LAST CDS_PHYS_NET_NAME IRQ_PCH_SCI_WHEA_N
J 0
(-450 -983);
PAINT MONO (-450 -983);
DISPLAY INVISIBLE (-450 -983);
FORCEPROP 0 LAST SIG_NAME IRQ_PCH_SCI_WHEA_N
J 0
(-135 -1015);
DISPLAY 0.680851 (-135 -1015);
PAINT WHITE (-135 -1015);
WIRE 16 -1 (-475 -1225)(950 -1225);
FORCEPROP 0 LAST CDS_PHYS_NET_NAME IRQ_PSU_ALERT_R_N
J 0
(-450 -1183);
PAINT MONO (-450 -1183);
DISPLAY INVISIBLE (-450 -1183);
FORCEPROP 0 LAST SIG_NAME IRQ_PSU_ALERT_R_N
J 0
(-135 -1215);
DISPLAY 0.680851 (-135 -1215);
PAINT WHITE (-135 -1215);
WIRE 16 -1 (-1125 2400)(-125 2400);
FORCEPROP 0 LAST CDS_PHYS_NET_NAME FM_BMC_READY_R_PLD_N
J 0
(-1100 2442);
PAINT MONO (-1100 2442);
DISPLAY INVISIBLE (-1100 2442);
FORCEPROP 0 LAST SIG_NAME FM_BMC_READY_R_PLD_N
J 0
(-985 2410);
DISPLAY 0.680851 (-985 2410);
PAINT WHITE (-985 2410);
WIRE 16 -1 (-475 700)(900 700);
FORCEPROP 2 LAST SIG_NAME RST_PCIE_PCH_DEV_PERST_M2_R_N
J 0
(-60 710);
DISPLAY 0.638298 (-60 710);
PAINT WHITE (-60 710);
WIRE 16 -1 (-1125 1850)(-125 1850);
FORCEPROP 0 LAST CDS_PHYS_NET_NAME PWRGD_SYS_PWROK_R
J 0
(-1100 1892);
PAINT MONO (-1100 1892);
DISPLAY INVISIBLE (-1100 1892);
FORCEPROP 0 LAST SIG_NAME HGX_DETECT_N_R
J 0
(-985 1860);
DISPLAY 0.680851 (-985 1860);
PAINT WHITE (-985 1860);
WIRE 16 -1 (-1125 1700)(-125 1700);
FORCEPROP 0 LAST CDS_PHYS_NET_NAME BMC_MONITER
J 0
(-1100 1742);
PAINT MONO (-1100 1742);
DISPLAY INVISIBLE (-1100 1742);
FORCEPROP 0 LAST SIG_NAME SWB_HSC_PWRGD_ISO_R
J 0
(-985 1710);
DISPLAY 0.680851 (-985 1710);
PAINT WHITE (-985 1710);
WIRE 16 -1 (-1125 2750)(-125 2750);
FORCEPROP 0 LAST CDS_PHYS_NET_NAME FM_THROTTLE_R_N
J 0
(-1100 2792);
PAINT MONO (-1100 2792);
DISPLAY INVISIBLE (-1100 2792);
FORCEPROP 0 LAST SIG_NAME FM_THROTTLE_R_N
J 0
(-985 2760);
DISPLAY 0.680851 (-985 2760);
PAINT WHITE (-985 2760);
WIRE 16 -1 (-1125 2850)(-125 2850);
FORCEPROP 0 LAST CDS_PHYS_NET_NAME FM_SPD_REMOTE_EN_R
J 0
(-1100 2892);
PAINT MONO (-1100 2892);
DISPLAY INVISIBLE (-1100 2892);
FORCEPROP 0 LAST SIG_NAME FM_SPD_REMOTE_EN_R
J 0
(-985 2860);
DISPLAY 0.680851 (-985 2860);
PAINT WHITE (-985 2860);
WIRE 16 -1 (-1125 2800)(-125 2800);
FORCEPROP 0 LAST CDS_PHYS_NET_NAME FM_P12V_HSC_ENABLE
J 0
(-1100 2842);
PAINT MONO (-1100 2842);
DISPLAY INVISIBLE (-1100 2842);
FORCEPROP 0 LAST SIG_NAME NC_FPGA_PB35B
J 0
(-985 2810);
DISPLAY 0.680851 (-985 2810);
WIRE 16 -1 (-475 350)(900 350);
FORCEPROP 0 LAST CDS_PHYS_NET_NAME BMC_MONITER_R
J 0
(-160 390);
PAINT MONO (-160 390);
DISPLAY INVISIBLE (-160 390);
FORCEPROP 2 LAST SIG_NAME HPDB_HSC_PWRGD_ISO_R
J 0
(-10 360);
DISPLAY 0.638298 (-10 360);
PAINT WHITE (-10 360);
WIRE 16 -1 (-475 525)(900 525);
FORCEPROP 0 LAST CDS_PHYS_NET_NAME BMC_MONITER_R
J 0
(-160 565);
PAINT MONO (-160 565);
DISPLAY INVISIBLE (-160 565);
FORCEPROP 2 LAST SIG_NAME HGX_DETECT_N
J 0
(-10 535);
DISPLAY 0.638298 (-10 535);
PAINT WHITE (-10 535);
WIRE 16 -1 (-475 875)(900 875);
FORCEPROP 0 LAST CDS_PHYS_NET_NAME FM_BMC_READY_R_N
J 0
(-160 915);
PAINT MONO (-160 915);
DISPLAY INVISIBLE (-160 915);
FORCEPROP 2 LAST SIG_NAME RST_PCIE_PCH_DEV_PERST_E1S_R_N
J 0
(-60 885);
DISPLAY 0.638298 (-60 885);
PAINT WHITE (-60 885);
WIRE 16 -1 (-475 -1575)(950 -1575);
FORCEPROP 2 LAST SIG_NAME FM_PDB_BUF_EN_R
J 0
(-110 -1565);
DISPLAY 0.638298 (-110 -1565);
PAINT WHITE (-110 -1565);
WIRE 16 -1 (-3900 2300)(-2875 2300);
FORCEPROP 0 LAST CDS_PHYS_NET_NAME USB_OC1_REAR_N
J 0
(-3875 2342);
PAINT MONO (-3875 2342);
DISPLAY INVISIBLE (-3875 2342);
FORCEPROP 0 LAST SIG_NAME USB_OC1_REAR_N
J 0
(-3860 2310);
DISPLAY 0.680851 (-3860 2310);
PAINT WHITE (-3860 2310);
WIRE 16 -1 (-1125 1600)(-125 1600);
FORCEPROP 0 LAST CDS_PHYS_NET_NAME PWRGD_SYS_PWROK_R
J 0
(-1100 1642);
PAINT MONO (-1100 1642);
DISPLAY INVISIBLE (-1100 1642);
FORCEPROP 0 LAST SIG_NAME NC_FPGA_PB46B
J 0
(-985 1610);
DISPLAY 0.680851 (-985 1610);
PAINT WHITE (-985 1610);
WIRE 16 -1 (-1125 1750)(-125 1750);
FORCEPROP 0 LAST CDS_PHYS_NET_NAME PWRGD_SYS_PWROK_R
J 0
(-1100 1792);
PAINT MONO (-1100 1792);
DISPLAY INVISIBLE (-1100 1792);
FORCEPROP 0 LAST SIG_NAME SWB_HSC_EN_R
J 0
(-985 1760);
DISPLAY 0.680851 (-985 1760);
PAINT WHITE (-985 1760);
WIRE 16 -1 (-1125 2250)(-125 2250);
FORCEPROP 0 LAST CDS_PHYS_NET_NAME JTAG_DBP_BMC_PREQ_R_N
J 0
(-1100 2292);
PAINT MONO (-1100 2292);
DISPLAY INVISIBLE (-1100 2292);
FORCEPROP 0 LAST SIG_NAME JTAG_DBP_BMC_PREQ_R_N
J 0
(-985 2260);
DISPLAY 0.680851 (-985 2260);
PAINT WHITE (-985 2260);
WIRE 16 -1 (-125 2200)(-1125 2200);
FORCEPROP 2 LAST SIG_NAME CLK_GPU_1_OE_N
J 0
(-985 2210);
DISPLAY 0.680851 (-985 2210);
PAINT WHITE (-985 2210);
WIRE 16 -1 (-1125 1900)(-125 1900);
FORCEPROP 2 LAST SIG_NAME NC_FPGA_PB43D
J 0
(-985 1910);
DISPLAY 0.680851 (-985 1910);
PAINT WHITE (-985 1910);
WIRE 16 -1 (-1125 2100)(-125 2100);
FORCEPROP 0 LAST CDS_PHYS_NET_NAME CLK_BB_OE_N
J 0
(-1100 2142);
PAINT MONO (-1100 2142);
DISPLAY INVISIBLE (-1100 2142);
FORCEPROP 0 LAST SIG_NAME CLK_SWB_OE_N
J 0
(-985 2110);
DISPLAY 0.680851 (-985 2110);
PAINT WHITE (-985 2110);
WIRE 16 -1 (-125 2150)(-1125 2150);
FORCEPROP 2 LAST SIG_NAME CLK_GPU_2_OE_N
J 0
(-985 2160);
DISPLAY 0.680851 (-985 2160);
PAINT WHITE (-985 2160);
WIRE 16 -1 (-1875 525)(-675 525);
FORCEPROP 0 LAST CDS_PHYS_NET_NAME BMC_MONITER
J 0
(-1850 567);
PAINT MONO (-1850 567);
DISPLAY INVISIBLE (-1850 567);
FORCEPROP 0 LAST SIG_NAME HGX_DETECT_N_R
J 0
(-1775 535);
DISPLAY 0.680851 (-1775 535);
PAINT WHITE (-1775 535);
WIRE 16 -1 (-1125 1950)(-125 1950);
FORCEPROP 2 LAST SIG_NAME CLK_SWB_BUF2_OE_N
J 0
(-985 1960);
DISPLAY 0.680851 (-985 1960);
PAINT WHITE (-985 1960);
WIRE 16 -1 (-125 2050)(-1125 2050);
FORCEPROP 2 LAST SIG_NAME CLK_GEN2_BMC_RC_OE_N
J 0
(-985 2060);
DISPLAY 0.680851 (-985 2060);
PAINT WHITE (-985 2060);
WIRE 16 -1 (775 2150)(775 2375);
WIRE 16 -1 (850 2375)(775 2375);
WIRE 16 -1 (500 2375)(775 2375);
WIRE 16 -1 (500 2375)(500 2000);
WIRE 16 -1 (-1125 2000)(500 2000);
FORCEPROP 0 LAST CDS_PHYS_NET_NAME FM_PLD_REV_N
J 0
(-275 2042);
PAINT MONO (-275 2042);
DISPLAY INVISIBLE (-275 2042);
FORCEPROP 0 LAST SIG_NAME FM_PLD_REV_N
J 0
(-985 2010);
DISPLAY 0.680851 (-985 2010);
PAINT WHITE (-985 2010);
WIRE 16 -1 (1775 2400)(1775 2375);
WIRE 16 -1 (1050 2375)(1775 2375);
FORCEPROP 0 LAST CDS_PHYS_NET_NAME FM_PLD_REV_R_N
J 0
(1075 2417);
PAINT MONO (1075 2417);
DISPLAY INVISIBLE (1075 2417);
FORCEPROP 0 LAST SIG_NAME FM_PLD_REV_R_N
J 0
(1365 2385);
DISPLAY 0.680851 (1365 2385);
PAINT WHITE (1365 2385);
WIRE 16 -1 (-475 -1400)(950 -1400);
FORCEPROP 0 LAST CDS_PHYS_NET_NAME FM_BMC_READY_R_N
J 0
(-160 -1360);
PAINT MONO (-160 -1360);
DISPLAY INVISIBLE (-160 -1360);
FORCEPROP 2 LAST SIG_NAME FM_BMC_READY_R_N
J 0
(-110 -1390);
DISPLAY 0.638298 (-110 -1390);
PAINT WHITE (-110 -1390);
WIRE 16 -1 (-125 1500)(-1125 1500);
FORCEPROP 2 LAST SIG_NAME FM_AC_PWR_BTN_PLD_ISO_N
J 0
(-985 1510);
DISPLAY 0.638298 (-985 1510);
PAINT RED (-985 1510);
WIRE 16 -1 (-925 700)(-675 700);
WIRE 16 -1 (-925 875)(-925 700);
WIRE 16 -1 (-925 875)(-675 875);
WIRE 16 -1 (-1800 875)(-925 875);
FORCEPROP 0 LAST CDS_PHYS_NET_NAME FM_BMC_READY_R_PLD_N
J 0
(-1775 917);
PAINT MONO (-1775 917);
DISPLAY INVISIBLE (-1775 917);
FORCEPROP 0 LAST SIG_NAME RST_PCIE_PCH_DEV_PERST_N
J 0
(-1700 885);
DISPLAY 0.680851 (-1700 885);
PAINT WHITE (-1700 885);
WIRE 16 -1 (1775 1650)(1775 1725);
WIRE 16 -1 (-1125 1650)(1775 1650);
FORCEPROP 2 LAST SIG_NAME PULL_FPGA_PB46A
J 0
(-985 1660);
DISPLAY 0.638298 (-985 1660);
PAINT WHITE (-985 1660);
WIRE 16 -1 (-1125 1550)(-125 1550);
FORCEPROP 2 LAST SIG_NAME FM_PDB_BUF_EN
J 0
(-985 1560);
DISPLAY 0.638298 (-985 1560);
PAINT WHITE (-985 1560);
WIRE 16 -1 (-1900 -125)(-700 -125);
FORCEPROP 0 LAST CDS_PHYS_NET_NAME BMC_MONITER
J 0
(-1875 -83);
PAINT MONO (-1875 -83);
DISPLAY INVISIBLE (-1875 -83);
FORCEPROP 0 LAST SIG_NAME SWB_HSC_PWRGD_ISO_R
J 0
(-1800 -115);
DISPLAY 0.680851 (-1800 -115);
PAINT WHITE (-1800 -115);
WIRE 16 -1 (-5725 350)(-4650 350);
FORCEPROP 0 LAST CDS_PHYS_NET_NAME CLK_25M_OSC_FPGA_R
J 0
(-5700 392);
PAINT MONO (-5700 392);
DISPLAY INVISIBLE (-5700 392);
FORCEPROP 0 LAST SIG_NAME GPU_3V3IO_RSVD1_FFU_ISO
J 0
(-5635 360);
DISPLAY 0.680851 (-5635 360);
PAINT WHITE (-5635 360);
WIRE 16 -1 (-5725 525)(-4650 525);
FORCEPROP 0 LAST CDS_PHYS_NET_NAME CLK_25M_OSC_FPGA_R
J 0
(-5700 567);
PAINT MONO (-5700 567);
DISPLAY INVISIBLE (-5700 567);
FORCEPROP 0 LAST SIG_NAME GPU_3V3IO_RSVD0_FFU_ISO
J 0
(-5635 535);
DISPLAY 0.680851 (-5635 535);
PAINT WHITE (-5635 535);
WIRE 16 -1 (-5725 700)(-4650 700);
FORCEPROP 0 LAST CDS_PHYS_NET_NAME BMC_MONITER
J 0
(-5700 742);
PAINT MONO (-5700 742);
DISPLAY INVISIBLE (-5700 742);
FORCEPROP 0 LAST SIG_NAME PRSNT_SWB_ISO_N
J 0
(-5625 710);
DISPLAY 0.680851 (-5625 710);
PAINT WHITE (-5625 710);
WIRE 16 -1 (-5725 25)(-4650 25);
FORCEPROP 0 LAST CDS_PHYS_NET_NAME CLK_25M_OSC_FPGA_R
J 0
(-5700 67);
PAINT MONO (-5700 67);
DISPLAY INVISIBLE (-5700 67);
FORCEPROP 0 LAST SIG_NAME GPU_3V3IO_RSVD3_FFU_ISO
J 0
(-5635 35);
DISPLAY 0.680851 (-5635 35);
PAINT WHITE (-5635 35);
WIRE 16 -1 (-5725 200)(-4650 200);
FORCEPROP 0 LAST CDS_PHYS_NET_NAME CLK_25M_OSC_FPGA_R
J 0
(-5700 242);
PAINT MONO (-5700 242);
DISPLAY INVISIBLE (-5700 242);
FORCEPROP 0 LAST SIG_NAME PRSNT_CABLE_GPU_B3_ISO_N
J 0
(-5635 210);
DISPLAY 0.680851 (-5635 210);
PAINT WHITE (-5635 210);
WIRE 16 -1 (-5725 -125)(-4650 -125);
FORCEPROP 0 LAST CDS_PHYS_NET_NAME CLK_25M_OSC_FPGA_R
J 0
(-5700 -83);
PAINT MONO (-5700 -83);
DISPLAY INVISIBLE (-5700 -83);
FORCEPROP 0 LAST SIG_NAME PRSNT_CABLE_GPU_A2_ISO_N
J 0
(-5635 -115);
DISPLAY 0.680851 (-5635 -115);
PAINT WHITE (-5635 -115);
WIRE 16 -1 (-5725 -950)(-4650 -950);
FORCEPROP 0 LAST CDS_PHYS_NET_NAME CLK_25M_OSC_FPGA_R
J 0
(-5700 -908);
PAINT MONO (-5700 -908);
DISPLAY INVISIBLE (-5700 -908);
FORCEPROP 0 LAST SIG_NAME GPU_3V3IO_RSVD4_ISO
J 0
(-5635 -940);
DISPLAY 0.680851 (-5635 -940);
PAINT WHITE (-5635 -940);
WIRE 16 -1 (-5725 -775)(-4650 -775);
FORCEPROP 0 LAST CDS_PHYS_NET_NAME CLK_25M_OSC_FPGA_R
J 0
(-5700 -733);
PAINT MONO (-5700 -733);
DISPLAY INVISIBLE (-5700 -733);
FORCEPROP 0 LAST SIG_NAME GPU_3V3IO_RSVD3_ISO
J 0
(-5635 -765);
DISPLAY 0.680851 (-5635 -765);
PAINT WHITE (-5635 -765);
WIRE 16 -1 (-5725 -600)(-4650 -600);
FORCEPROP 0 LAST CDS_PHYS_NET_NAME CLK_25M_OSC_FPGA_R
J 0
(-5700 -558);
PAINT MONO (-5700 -558);
DISPLAY INVISIBLE (-5700 -558);
FORCEPROP 0 LAST SIG_NAME GPU_3V3IO_RSVD1_ISO
J 0
(-5635 -590);
DISPLAY 0.680851 (-5635 -590);
PAINT WHITE (-5635 -590);
WIRE 16 -1 (-5725 -300)(-4650 -300);
FORCEPROP 0 LAST CDS_PHYS_NET_NAME CLK_25M_OSC_FPGA_R
J 0
(-5700 -258);
PAINT MONO (-5700 -258);
DISPLAY INVISIBLE (-5700 -258);
FORCEPROP 0 LAST SIG_NAME GPU_3V3IO_RSVD5_FFU_ISO
J 0
(-5635 -290);
DISPLAY 0.680851 (-5635 -290);
PAINT WHITE (-5635 -290);
WIRE 16 -1 (-5725 -475)(-4650 -475);
FORCEPROP 0 LAST CDS_PHYS_NET_NAME CLK_25M_OSC_FPGA_R
J 0
(-5700 -433);
PAINT MONO (-5700 -433);
DISPLAY INVISIBLE (-5700 -433);
FORCEPROP 0 LAST SIG_NAME PRSNT_CABLE_GPU_A1_ISO_N
J 0
(-5635 -465);
DISPLAY 0.680851 (-5635 -465);
PAINT WHITE (-5635 -465);
WIRE 16 -1 (-3900 1650)(-2875 1650);
FORCEPROP 0 LAST CDS_PHYS_NET_NAME CLK_25M_OSC_MAIN_FPGA
J 0
(-3875 1692);
PAINT MONO (-3875 1692);
DISPLAY INVISIBLE (-3875 1692);
FORCEPROP 0 LAST SIG_NAME GPU_3V3IO_RSVD1_FFU_ISO_R
J 0
(-3860 1660);
DISPLAY 0.680851 (-3860 1660);
PAINT WHITE (-3860 1660);
WIRE 16 -1 (-3900 1700)(-2875 1700);
FORCEPROP 0 LAST CDS_PHYS_NET_NAME CLK_25M_OSC_MAIN_FPGA
J 0
(-3875 1742);
PAINT MONO (-3875 1742);
DISPLAY INVISIBLE (-3875 1742);
FORCEPROP 0 LAST SIG_NAME GPU_3V3IO_RSVD0_FFU_ISO_R
J 0
(-3860 1710);
DISPLAY 0.680851 (-3860 1710);
PAINT WHITE (-3860 1710);
WIRE 16 -1 (-3900 1750)(-2875 1750);
FORCEPROP 0 LAST CDS_PHYS_NET_NAME PWRGD_SYS_PWROK_R
J 0
(-3875 1792);
PAINT MONO (-3875 1792);
DISPLAY INVISIBLE (-3875 1792);
FORCEPROP 0 LAST SIG_NAME NC_FPGA_PB22B
J 0
(-3860 1760);
DISPLAY 0.680851 (-3860 1760);
PAINT WHITE (-3860 1760);
WIRE 16 -1 (-3900 1550)(-2875 1550);
FORCEPROP 0 LAST CDS_PHYS_NET_NAME CLK_25M_OSC_MAIN_FPGA
J 0
(-3875 1592);
PAINT MONO (-3875 1592);
DISPLAY INVISIBLE (-3875 1592);
FORCEPROP 0 LAST SIG_NAME GPU_3V3IO_RSVD3_FFU_ISO_R
J 0
(-3860 1560);
DISPLAY 0.680851 (-3860 1560);
PAINT WHITE (-3860 1560);
WIRE 16 -1 (-4450 -125)(-3225 -125);
FORCEPROP 0 LAST CDS_PHYS_NET_NAME CLK_25M_OSC_MAIN_FPGA
J 0
(-4425 -83);
PAINT MONO (-4425 -83);
DISPLAY INVISIBLE (-4425 -83);
FORCEPROP 0 LAST SIG_NAME PRSNT_CABLE_GPU_A2_ISO_R_N
J 0
(-4060 -115);
DISPLAY 0.680851 (-4060 -115);
PAINT WHITE (-4060 -115);
WIRE 16 -1 (-4450 25)(-3225 25);
FORCEPROP 0 LAST CDS_PHYS_NET_NAME CLK_25M_OSC_MAIN_FPGA
J 0
(-4425 67);
PAINT MONO (-4425 67);
DISPLAY INVISIBLE (-4425 67);
FORCEPROP 0 LAST SIG_NAME GPU_3V3IO_RSVD3_FFU_ISO_R
J 0
(-4060 35);
DISPLAY 0.680851 (-4060 35);
PAINT WHITE (-4060 35);
WIRE 16 -1 (-4450 200)(-3225 200);
FORCEPROP 0 LAST CDS_PHYS_NET_NAME CLK_25M_OSC_MAIN_FPGA
J 0
(-4425 242);
PAINT MONO (-4425 242);
DISPLAY INVISIBLE (-4425 242);
FORCEPROP 0 LAST SIG_NAME PRSNT_CABLE_GPU_B3_ISO_R_N
J 0
(-4060 210);
DISPLAY 0.680851 (-4060 210);
PAINT WHITE (-4060 210);
WIRE 16 -1 (-4450 700)(-3250 700);
FORCEPROP 0 LAST CDS_PHYS_NET_NAME BMC_MONITER_R
J 0
(-4135 740);
PAINT MONO (-4135 740);
DISPLAY INVISIBLE (-4135 740);
FORCEPROP 2 LAST SIG_NAME PRSNT_SWB_ISO_R_N
J 0
(-4060 710);
DISPLAY 0.638298 (-4060 710);
PAINT WHITE (-4060 710);
WIRE 16 -1 (-4450 875)(-3250 875);
FORCEPROP 0 LAST CDS_PHYS_NET_NAME BMC_MONITER_R
J 0
(-4135 915);
PAINT MONO (-4135 915);
DISPLAY INVISIBLE (-4135 915);
FORCEPROP 2 LAST SIG_NAME HSC_D_OC_R1
J 0
(-4060 885);
DISPLAY 0.638298 (-4060 885);
PAINT WHITE (-4060 885);
WIRE 16 -1 (-1875 175)(-675 175);
FORCEPROP 0 LAST CDS_PHYS_NET_NAME BMC_MONITER
J 0
(-1850 217);
PAINT MONO (-1850 217);
DISPLAY INVISIBLE (-1850 217);
FORCEPROP 0 LAST SIG_NAME SWB_HSC_EN
J 0
(-1775 185);
DISPLAY 0.680851 (-1775 185);
PAINT WHITE (-1775 185);
WIRE 16 2175 (-2275 50)(1325 50);
WIRE 16 2175 (1325 50)(1325 -275);
WIRE 16 2175 (-2275 50)(-2275 -275);
WIRE 16 2175 (-2275 -275)(1325 -275);
WIRE 16 -1 (-4450 -600)(-3225 -600);
FORCEPROP 0 LAST CDS_PHYS_NET_NAME CLK_25M_OSC_MAIN_FPGA
J 0
(-4425 -558);
PAINT MONO (-4425 -558);
DISPLAY INVISIBLE (-4425 -558);
FORCEPROP 0 LAST SIG_NAME GPU_3V3IO_RSVD1_ISO_R
J 0
(-4060 -590);
DISPLAY 0.680851 (-4060 -590);
PAINT WHITE (-4060 -590);
WIRE 16 -1 (-4450 -300)(-3225 -300);
FORCEPROP 0 LAST CDS_PHYS_NET_NAME CLK_25M_OSC_MAIN_FPGA
J 0
(-4425 -258);
PAINT MONO (-4425 -258);
DISPLAY INVISIBLE (-4425 -258);
FORCEPROP 0 LAST SIG_NAME GPU_3V3IO_RSVD5_FFU_ISO_R
J 0
(-4060 -290);
DISPLAY 0.680851 (-4060 -290);
PAINT WHITE (-4060 -290);
WIRE 16 -1 (-4450 -775)(-3225 -775);
FORCEPROP 0 LAST CDS_PHYS_NET_NAME CLK_25M_OSC_MAIN_FPGA
J 0
(-4425 -733);
PAINT MONO (-4425 -733);
DISPLAY INVISIBLE (-4425 -733);
FORCEPROP 0 LAST SIG_NAME GPU_3V3IO_RSVD3_ISO_R
J 0
(-4060 -765);
DISPLAY 0.680851 (-4060 -765);
PAINT WHITE (-4060 -765);
WIRE 16 -1 (-4450 -475)(-3225 -475);
FORCEPROP 0 LAST CDS_PHYS_NET_NAME CLK_25M_OSC_MAIN_FPGA
J 0
(-4425 -433);
PAINT MONO (-4425 -433);
DISPLAY INVISIBLE (-4425 -433);
FORCEPROP 0 LAST SIG_NAME PRSNT_CABLE_GPU_A1_ISO_R_N
J 0
(-4060 -465);
DISPLAY 0.680851 (-4060 -465);
PAINT WHITE (-4060 -465);
WIRE 16 -1 (-3900 1250)(-2875 1250);
FORCEPROP 0 LAST CDS_PHYS_NET_NAME CLK_25M_OSC_MAIN_FPGA
J 0
(-3875 1292);
PAINT MONO (-3875 1292);
DISPLAY INVISIBLE (-3875 1292);
FORCEPROP 0 LAST SIG_NAME GPU_3V3IO_RSVD4_ISO_R
J 0
(-3860 1260);
DISPLAY 0.680851 (-3860 1260);
PAINT WHITE (-3860 1260);
WIRE 16 -1 (-3900 1300)(-2875 1300);
FORCEPROP 0 LAST CDS_PHYS_NET_NAME CLK_25M_OSC_MAIN_FPGA
J 0
(-3875 1342);
PAINT MONO (-3875 1342);
DISPLAY INVISIBLE (-3875 1342);
FORCEPROP 0 LAST SIG_NAME GPU_3V3IO_RSVD3_ISO_R
J 0
(-3860 1310);
DISPLAY 0.680851 (-3860 1310);
PAINT WHITE (-3860 1310);
WIRE 16 -1 (-3900 1500)(-2875 1500);
FORCEPROP 0 LAST CDS_PHYS_NET_NAME CLK_25M_OSC_MAIN_FPGA
J 0
(-3875 1542);
PAINT MONO (-3875 1542);
DISPLAY INVISIBLE (-3875 1542);
FORCEPROP 0 LAST SIG_NAME PRSNT_CABLE_GPU_A2_ISO_R_N
J 0
(-3860 1510);
DISPLAY 0.680851 (-3860 1510);
PAINT WHITE (-3860 1510);
WIRE 16 -1 (-3900 1450)(-2875 1450);
FORCEPROP 0 LAST CDS_PHYS_NET_NAME CLK_25M_OSC_MAIN_FPGA
J 0
(-3875 1492);
PAINT MONO (-3875 1492);
DISPLAY INVISIBLE (-3875 1492);
FORCEPROP 0 LAST SIG_NAME GPU_3V3IO_RSVD5_FFU_ISO_R
J 0
(-3860 1460);
DISPLAY 0.680851 (-3860 1460);
PAINT WHITE (-3860 1460);
WIRE 16 -1 (-3900 1350)(-2875 1350);
FORCEPROP 0 LAST CDS_PHYS_NET_NAME CLK_25M_OSC_MAIN_FPGA
J 0
(-3875 1392);
PAINT MONO (-3875 1392);
DISPLAY INVISIBLE (-3875 1392);
FORCEPROP 0 LAST SIG_NAME GPU_3V3IO_RSVD1_ISO_R
J 0
(-3860 1360);
DISPLAY 0.680851 (-3860 1360);
PAINT WHITE (-3860 1360);
WIRE 16 -1 (-3900 1400)(-2875 1400);
FORCEPROP 0 LAST CDS_PHYS_NET_NAME CLK_25M_OSC_MAIN_FPGA
J 0
(-3875 1442);
PAINT MONO (-3875 1442);
DISPLAY INVISIBLE (-3875 1442);
FORCEPROP 0 LAST SIG_NAME PRSNT_CABLE_GPU_A1_ISO_R_N
J 0
(-3860 1410);
DISPLAY 0.680851 (-3860 1410);
PAINT WHITE (-3860 1410);
WIRE 16 -1 (-4450 350)(-3225 350);
FORCEPROP 0 LAST CDS_PHYS_NET_NAME CLK_25M_OSC_MAIN_FPGA
J 0
(-4425 392);
PAINT MONO (-4425 392);
DISPLAY INVISIBLE (-4425 392);
FORCEPROP 0 LAST SIG_NAME GPU_3V3IO_RSVD1_FFU_ISO_R
J 0
(-4060 360);
DISPLAY 0.680851 (-4060 360);
PAINT WHITE (-4060 360);
DOT 1 (775 2375);
DOT 1 (-925 875);
FORCENOTE
20211130 ADD RES TO FPGA
(-5950 -1125) 0;
DISPLAY LEFT (-5950 -1125);
DISPLAY 1.063830 (-5950 -1125);
PAINT WHITE (-5950 -1125);
FORCENOTE
20210902 MODIFY FOR GT
(-6175 4300) 0;
DISPLAY LEFT (-6175 4300);
DISPLAY 2.510638 (-6175 4300);
PAINT PINK (-6175 4300);
FORCENOTE
2-3 DISABLE (DEFAULT)
(-6150 2700) 0;
DISPLAY LEFT (-6150 2700);
DISPLAY 1.021277 (-6150 2700);
PAINT WHITE (-6150 2700);
FORCENOTE
20220224 ADD JP15
(-5250 3300) 0;
DISPLAY LEFT (-5250 3300);
DISPLAY 1.021277 (-5250 3300);
PAINT PINK (-5250 3300);
FORCENOTE
1-2 ENABLE 
(-6150 2825) 0;
DISPLAY LEFT (-6150 2825);
DISPLAY 1.021277 (-6150 2825);
PAINT WHITE (-6150 2825);
FORCENOTE
FORCE_PWRON_JUMPER
(-6150 2950) 0;
DISPLAY LEFT (-6150 2950);
DISPLAY 1.021277 (-6150 2950);
PAINT WHITE (-6150 2950);
FORCENOTE
20220103 ADD R4563
(-1025 -375) 0;
DISPLAY LEFT (-1025 -375);
DISPLAY 1.063830 (-1025 -375);
PAINT WHITE (-1025 -375);
FORCENOTE
20220727 CONNECT TO CPLD.V17
(-2075 -1750) 0;
DISPLAY LEFT (-2075 -1750);
DISPLAY 1.063830 (-2075 -1750);
PAINT WHITE (-2075 -1750);
FORCENOTE
20220801 ADD R4723
(-4100 -1950) 0;
DISPLAY LEFT (-4100 -1950);
DISPLAY 1.063830 (-4100 -1950);
PAINT WHITE (-4100 -1950);
QUIT
